G04 ================== begin FILE IDENTIFICATION RECORD ==================*
G04 Layout Name:  9054_F0T_PDB_BD_GPU_F_V04_1213_1550.brd*
G04 Film Name:    panel*
G04 File Format:  Gerber RS274X*
G04 File Origin:  Cadence Allegro 17.2-S081*
G04 Origin Date:  Wed Dec 28 10:19:02 2022*
G04 *
G04 Layer:  DRAWING FORMAT/TITLE_BLOCK_A*
G04 Layer:  MANUFACTURING/PHOTOPLOT_OUTLINE*
G04 Layer:  DRAWING FORMAT/TITLE_BLOCK*
G04 Layer:  DRAWING FORMAT/TITLE_DATA_PANEL*
G04 Layer:  BOARD GEOMETRY/ASSEMBLY_NOTES*
G04 *
G04 Offset:    (0.00 0.00)*
G04 Mirror:    No*
G04 Mode:      Positive*
G04 Rotation:  0*
G04 FullContactRelief:  No*
G04 UndefLineWidth:     6.00*
G04 ================== end FILE IDENTIFICATION RECORD ====================*
%FSLAX25Y25*MOIN*%
%IR0*IPPOS*OFA0.00000B0.00000*MIA0B0*SFA1.00000B1.00000*%
%ADD10C,.1*%
%ADD11C,.006*%
G75*
%LPD*%
G75*
G36*
G01X21653Y738607D02*
G02I-1968J0D01*
G37*
G36*
G01X1856300Y-726796D02*
G02I-1969J0D01*
G37*
G36*
G01X2191882Y-550390D02*
G02I-1969J0D01*
G37*
G54D10*
G01X978500Y307500D02*
X820000D01*
Y112000D01*
G01Y209750D02*
X962750D01*
G01X895516Y-315374D02*
X1054016D01*
Y-119874D01*
G01Y-217624D02*
X911266D01*
G54D11*
G01X-457143Y-1211429D02*
Y2242857D01*
X4308572D01*
Y-1211429D01*
X-457143D01*
G01X7874Y-793725D02*
G02X0Y-785851I0J7874D01*
G01Y-744725D01*
G01X31496Y-793725D02*
X7874D01*
G01X122048Y-534528D02*
X7874D01*
G03X0Y-542402I0J-7874D01*
G01Y-744725D01*
G01Y-506968D02*
G03X19685Y-526654I19686J-1D01*
G01X0Y-93583D02*
Y-506968D01*
G01X19685Y-73898D02*
G03X0Y-93583I0J-19685D01*
G01Y603543D02*
Y19685D01*
G01D02*
G03X19685Y0I19685J0D01*
G01X92220Y631102D02*
X7874D01*
G02X0Y638976I0J7874D01*
G01Y724851D01*
G01X19685Y623228D02*
G03X0Y603543I0J-19685D01*
G01Y694594D02*
Y884800D01*
G01Y724851D02*
Y777977D01*
G02X7874Y785851I7874J0D01*
G01D02*
X1842520D01*
G01X891575Y883800D02*
X0D01*
G01X5000Y884800D02*
X0Y883800D01*
X5000Y882800D01*
Y884800D01*
G01X37000Y-995000D02*
Y-1070000D01*
X537000D01*
Y-995000D01*
X37000D01*
G01X31496Y-793725D02*
X1842520D01*
G01X19685Y-526654D02*
X122047D01*
G01X31496Y-534528D02*
G03Y-526654I0J3937D01*
G01X122047Y-73898D02*
X19685D01*
G01Y0D02*
X1712598D01*
G01X102362Y623228D02*
X19685D01*
G01X49000Y-1060000D02*
Y-1065000D01*
G01X47543Y-1060000D02*
X50457D01*
G01X55367Y-1065000D02*
X52833D01*
Y-1060000D01*
X55367D01*
G01X54353Y-1062417D02*
X52833D01*
G01X57933Y-1060000D02*
Y-1065000D01*
X60467D01*
G01X64300Y-1065167D02*
X64173Y-1065083D01*
Y-1064917D01*
X64300Y-1064833D01*
X64427Y-1064917D01*
Y-1065083D01*
X64300Y-1065167D01*
G01Y-1062917D02*
X64173Y-1062833D01*
Y-1062667D01*
X64300Y-1062583D01*
X64427Y-1062667D01*
Y-1062833D01*
X64300Y-1062917D01*
G01X69083Y-1066667D02*
X68450Y-1065833D01*
X68133Y-1065000D01*
Y-1061667D01*
X68450Y-1060833D01*
X69083Y-1060000D01*
G01X74500D02*
X73993Y-1060167D01*
X73613Y-1060583D01*
X73360Y-1061083D01*
X73170Y-1061750D01*
X73107Y-1062500D01*
X73170Y-1063250D01*
X73360Y-1063917D01*
X73613Y-1064417D01*
X73993Y-1064833D01*
X74500Y-1065000D01*
X75007Y-1064833D01*
X75387Y-1064417D01*
X75640Y-1063917D01*
X75830Y-1063250D01*
X75893Y-1062500D01*
X75830Y-1061750D01*
X75640Y-1061083D01*
X75387Y-1060583D01*
X75007Y-1060167D01*
X74500Y-1060000D01*
G01X78207Y-1064000D02*
X78587Y-1064583D01*
X79093Y-1064917D01*
X79663Y-1065000D01*
X80170Y-1064917D01*
X80677Y-1064500D01*
X80993Y-1064000D01*
X81057Y-1063500D01*
X80930Y-1062917D01*
X80487Y-1062500D01*
X80043Y-1062333D01*
X79473D01*
G01X80043D02*
X80423Y-1062083D01*
X80740Y-1061667D01*
X80867Y-1061167D01*
X80740Y-1060667D01*
X80423Y-1060250D01*
X79853Y-1060000D01*
X79283Y-1060083D01*
X78713Y-1060417D01*
G01X85017Y-1066667D02*
X85650Y-1065833D01*
X85967Y-1065000D01*
Y-1061667D01*
X85650Y-1060833D01*
X85017Y-1060000D01*
G01X88407Y-1064000D02*
X88787Y-1064583D01*
X89293Y-1064917D01*
X89863Y-1065000D01*
X90370Y-1064917D01*
X90877Y-1064500D01*
X91193Y-1064000D01*
X91257Y-1063500D01*
X91130Y-1062917D01*
X90687Y-1062500D01*
X90243Y-1062333D01*
X89673D01*
G01X90243D02*
X90623Y-1062083D01*
X90940Y-1061667D01*
X91067Y-1061167D01*
X90940Y-1060667D01*
X90623Y-1060250D01*
X90053Y-1060000D01*
X89483Y-1060083D01*
X88913Y-1060417D01*
G01X93697Y-1060833D02*
X94077Y-1060333D01*
X94520Y-1060083D01*
X95027Y-1060000D01*
X95660Y-1060167D01*
X96103Y-1060583D01*
X96230Y-1061083D01*
X96167Y-1061583D01*
X95913Y-1062000D01*
X94647Y-1062833D01*
X94077Y-1063417D01*
X93697Y-1064250D01*
X93570Y-1065000D01*
X96230D01*
G01X99873D02*
X100000Y-1063917D01*
X100190Y-1063000D01*
X100443Y-1062167D01*
X100760Y-1061250D01*
X101267Y-1060000D01*
X98733D01*
G01X104277Y-1063333D02*
X105923D01*
G01X108997Y-1060833D02*
X109377Y-1060333D01*
X109820Y-1060083D01*
X110327Y-1060000D01*
X110960Y-1060167D01*
X111403Y-1060583D01*
X111530Y-1061083D01*
X111467Y-1061583D01*
X111213Y-1062000D01*
X109947Y-1062833D01*
X109377Y-1063417D01*
X108997Y-1064250D01*
X108870Y-1065000D01*
X111530D01*
G01X113907Y-1064000D02*
X114287Y-1064583D01*
X114793Y-1064917D01*
X115363Y-1065000D01*
X115870Y-1064917D01*
X116377Y-1064500D01*
X116693Y-1064000D01*
X116757Y-1063500D01*
X116630Y-1062917D01*
X116187Y-1062500D01*
X115743Y-1062333D01*
X115173D01*
G01X115743D02*
X116123Y-1062083D01*
X116440Y-1061667D01*
X116567Y-1061167D01*
X116440Y-1060667D01*
X116123Y-1060250D01*
X115553Y-1060000D01*
X114983Y-1060083D01*
X114413Y-1060417D01*
G01X121160Y-1065000D02*
Y-1060000D01*
X118817Y-1063583D01*
X121983D01*
G01X124107Y-1064250D02*
X124487Y-1064667D01*
X124930Y-1064917D01*
X125500Y-1065000D01*
X126070Y-1064833D01*
X126513Y-1064500D01*
X126830Y-1063917D01*
X126893Y-1063250D01*
X126767Y-1062583D01*
X126450Y-1062167D01*
X126007Y-1061833D01*
X125563Y-1061750D01*
X125120Y-1061833D01*
X124550Y-1062167D01*
X124740Y-1060000D01*
X126450D01*
G01X134497Y-1065000D02*
Y-1060000D01*
X136903D01*
G01X136017Y-1062417D02*
X134497D01*
G01X139217Y-1065000D02*
X140800Y-1060000D01*
X142383Y-1065000D01*
G01X141813Y-1063250D02*
X139787D01*
G01X144570Y-1065000D02*
X147230Y-1060000D01*
G01X144570D02*
X147230Y-1065000D01*
G01X151000Y-1065167D02*
X150873Y-1065083D01*
Y-1064917D01*
X151000Y-1064833D01*
X151127Y-1064917D01*
Y-1065083D01*
X151000Y-1065167D01*
G01Y-1062917D02*
X150873Y-1062833D01*
Y-1062667D01*
X151000Y-1062583D01*
X151127Y-1062667D01*
Y-1062833D01*
X151000Y-1062917D01*
G01X155783Y-1066667D02*
X155150Y-1065833D01*
X154833Y-1065000D01*
Y-1061667D01*
X155150Y-1060833D01*
X155783Y-1060000D01*
G01X161200D02*
X160693Y-1060167D01*
X160313Y-1060583D01*
X160060Y-1061083D01*
X159870Y-1061750D01*
X159807Y-1062500D01*
X159870Y-1063250D01*
X160060Y-1063917D01*
X160313Y-1064417D01*
X160693Y-1064833D01*
X161200Y-1065000D01*
X161707Y-1064833D01*
X162087Y-1064417D01*
X162340Y-1063917D01*
X162530Y-1063250D01*
X162593Y-1062500D01*
X162530Y-1061750D01*
X162340Y-1061083D01*
X162087Y-1060583D01*
X161707Y-1060167D01*
X161200Y-1060000D01*
G01X164907Y-1064000D02*
X165287Y-1064583D01*
X165793Y-1064917D01*
X166363Y-1065000D01*
X166870Y-1064917D01*
X167377Y-1064500D01*
X167693Y-1064000D01*
X167757Y-1063500D01*
X167630Y-1062917D01*
X167187Y-1062500D01*
X166743Y-1062333D01*
X166173D01*
G01X166743D02*
X167123Y-1062083D01*
X167440Y-1061667D01*
X167567Y-1061167D01*
X167440Y-1060667D01*
X167123Y-1060250D01*
X166553Y-1060000D01*
X165983Y-1060083D01*
X165413Y-1060417D01*
G01X171717Y-1066667D02*
X172350Y-1065833D01*
X172667Y-1065000D01*
Y-1061667D01*
X172350Y-1060833D01*
X171717Y-1060000D01*
G01X175107Y-1064000D02*
X175487Y-1064583D01*
X175993Y-1064917D01*
X176563Y-1065000D01*
X177070Y-1064917D01*
X177577Y-1064500D01*
X177893Y-1064000D01*
X177957Y-1063500D01*
X177830Y-1062917D01*
X177387Y-1062500D01*
X176943Y-1062333D01*
X176373D01*
G01X176943D02*
X177323Y-1062083D01*
X177640Y-1061667D01*
X177767Y-1061167D01*
X177640Y-1060667D01*
X177323Y-1060250D01*
X176753Y-1060000D01*
X176183Y-1060083D01*
X175613Y-1060417D01*
G01X180523Y-1064417D02*
X180967Y-1064833D01*
X181473Y-1065000D01*
X181980Y-1064833D01*
X182423Y-1064333D01*
X182740Y-1063583D01*
X182867Y-1062833D01*
Y-1061917D01*
X182740Y-1061167D01*
X182423Y-1060500D01*
X182043Y-1060167D01*
X181600Y-1060000D01*
X181093Y-1060167D01*
X180713Y-1060500D01*
X180460Y-1061000D01*
X180333Y-1061667D01*
X180460Y-1062250D01*
X180777Y-1062833D01*
X181157Y-1063167D01*
X181600Y-1063250D01*
X182107Y-1063083D01*
X182487Y-1062667D01*
X182867Y-1061917D01*
G01X186573Y-1065000D02*
X186700Y-1063917D01*
X186890Y-1063000D01*
X187143Y-1062167D01*
X187460Y-1061250D01*
X187967Y-1060000D01*
X185433D01*
G01X190977Y-1063333D02*
X192623D01*
G01X195507Y-1064000D02*
X195887Y-1064583D01*
X196393Y-1064917D01*
X196963Y-1065000D01*
X197470Y-1064917D01*
X197977Y-1064500D01*
X198293Y-1064000D01*
X198357Y-1063500D01*
X198230Y-1062917D01*
X197787Y-1062500D01*
X197343Y-1062333D01*
X196773D01*
G01X197343D02*
X197723Y-1062083D01*
X198040Y-1061667D01*
X198167Y-1061167D01*
X198040Y-1060667D01*
X197723Y-1060250D01*
X197153Y-1060000D01*
X196583Y-1060083D01*
X196013Y-1060417D01*
G01X200797Y-1062917D02*
X201240Y-1062333D01*
X201620Y-1062000D01*
X202127Y-1061833D01*
X202570Y-1062000D01*
X202887Y-1062333D01*
X203140Y-1062833D01*
X203203Y-1063417D01*
X203140Y-1063917D01*
X202887Y-1064417D01*
X202507Y-1064833D01*
X202063Y-1065000D01*
X201557Y-1064833D01*
X201113Y-1064333D01*
X200860Y-1063583D01*
X200797Y-1062750D01*
X200923Y-1061667D01*
X201113Y-1061083D01*
X201430Y-1060500D01*
X201873Y-1060083D01*
X202317Y-1060000D01*
X202760Y-1060167D01*
X203077Y-1060583D01*
G01X207100Y-1065000D02*
Y-1060000D01*
X206340Y-1061000D01*
G01Y-1065000D02*
X207860D01*
G01X212960D02*
Y-1060000D01*
X210617Y-1063583D01*
X213783D01*
G01X51182Y-534528D02*
G02Y-526654I0J3937D01*
G01X51181Y623228D02*
G03Y631102I0J3937D01*
G01X70867Y623228D02*
G02Y631102I0J3937D01*
G01X92220D02*
G03X104031Y642913I0J11811D01*
G01X122047D02*
G02X102362Y623228I-19685J0D01*
G01X104031Y738607D02*
Y642913D01*
G01X111905Y746481D02*
G03X104031Y738607I0J-7874D01*
G01X161418Y-638976D02*
G02X133859Y-611417I0J27559D01*
G01D02*
Y-546339D01*
G01Y-588721D02*
G02X141733I3937J0D01*
G01X133859Y-569035D02*
G03X141733I3937J0D01*
G01X133859Y-546339D02*
G03X122048Y-534528I-11811J0D01*
G01X122047Y-526654D02*
G02X141733Y-546339I1J-19686D01*
G01Y-54213D02*
G02X122047Y-73898I-19686J1D01*
G01X141732Y675787D02*
G03X122047Y656102I0J-19685D01*
G01D02*
Y642913D01*
G01X348425Y746481D02*
X111905D01*
G01X233952Y-638976D02*
X161418D01*
G01X141733Y-546339D02*
Y-611417D01*
G01X161418Y-631102D02*
X244095D01*
G01X141733Y-611417D02*
G03X161418Y-631102I19685J0D01*
G01X141733Y-27559D02*
Y-54213D01*
G01X1854331Y-7874D02*
X161418D01*
G01D02*
G03X141733Y-27559I0J-19685D01*
G01X161418Y-7874D02*
G03Y0I0J3937D01*
G01X295276Y675787D02*
X141732D01*
G01X192913Y-638976D02*
G03Y-631102I0J3937D01*
G01X181104Y-7874D02*
G02Y0I0J3937D01*
G01X212599Y-638976D02*
G02Y-631102I0J3937D01*
G01X232000Y-995000D02*
Y-1070000D01*
G01Y-1045000D02*
X335000D01*
Y-1020000D01*
G01X232000D02*
X335000D01*
G01X253637Y-754355D02*
X490158D01*
G01X245763Y-650787D02*
Y-746481D01*
G01D02*
G03X253637Y-754355I7874J0D01*
G01X245763Y-650787D02*
G03X233952Y-638976I-11811J0D01*
G01X244095Y-631102D02*
G02X263780Y-650787I0J-19685D01*
G01X283465Y-683661D02*
X437008D01*
G01X263780Y-663976D02*
G03X283465Y-683661I19685J0D01*
G01X263780Y-650787D02*
Y-663976D01*
G01X326772Y623228D02*
G02X314961Y635039I0J11811D01*
G01D02*
Y656102D01*
G01D02*
G03X295276Y675787I-19685J0D01*
G01X337000Y-995000D02*
Y-1070000D01*
G01X335000Y-995000D02*
Y-1070000D01*
G01X342507Y-1055000D02*
Y-1050000D01*
X343773D01*
X344280Y-1050250D01*
X344660Y-1050583D01*
X344977Y-1051083D01*
X345230Y-1051667D01*
X345293Y-1052500D01*
X345230Y-1053333D01*
X344977Y-1053917D01*
X344660Y-1054417D01*
X344280Y-1054750D01*
X343773Y-1055000D01*
X342507D01*
G01X347417D02*
X349000Y-1050000D01*
X350583Y-1055000D01*
G01X350013Y-1053250D02*
X347987D01*
G01X354100Y-1050000D02*
Y-1055000D01*
G01X352643Y-1050000D02*
X355557D01*
G01X360467Y-1055000D02*
X357933D01*
Y-1050000D01*
X360467D01*
G01X359453Y-1052417D02*
X357933D01*
G01X364300Y-1055167D02*
X364173Y-1055083D01*
Y-1054917D01*
X364300Y-1054833D01*
X364427Y-1054917D01*
Y-1055083D01*
X364300Y-1055167D01*
G01Y-1052917D02*
X364173Y-1052833D01*
Y-1052667D01*
X364300Y-1052583D01*
X364427Y-1052667D01*
Y-1052833D01*
X364300Y-1052917D01*
G01X337000Y-1045000D02*
X537000D01*
G01X342633Y-1030000D02*
Y-1025000D01*
X344153D01*
X344660Y-1025250D01*
X345040Y-1025833D01*
X345167Y-1026500D01*
X345040Y-1027167D01*
X344723Y-1027667D01*
X344153Y-1027917D01*
X342633D01*
G01X347860Y-1030167D02*
X350140Y-1025000D01*
G01X352643Y-1030000D02*
Y-1025000D01*
X355557Y-1030000D01*
Y-1025000D01*
G01X359200Y-1030167D02*
X359073Y-1030083D01*
Y-1029917D01*
X359200Y-1029833D01*
X359327Y-1029917D01*
Y-1030083D01*
X359200Y-1030167D01*
G01Y-1027917D02*
X359073Y-1027833D01*
Y-1027667D01*
X359200Y-1027583D01*
X359327Y-1027667D01*
Y-1027833D01*
X359200Y-1027917D01*
G01X342633Y-1005000D02*
Y-1000000D01*
X344153D01*
X344660Y-1000250D01*
X345040Y-1000833D01*
X345167Y-1001500D01*
X345040Y-1002167D01*
X344723Y-1002667D01*
X344153Y-1002917D01*
X342633D01*
G01X347733Y-1005000D02*
Y-1000000D01*
X349317D01*
X349823Y-1000250D01*
X350140Y-1000583D01*
X350267Y-1001250D01*
X350140Y-1001917D01*
X349760Y-1002333D01*
X349317Y-1002583D01*
X347733D01*
G01X349317D02*
X350267Y-1005000D01*
G01X354100D02*
X353593Y-1004917D01*
X353150Y-1004583D01*
X352770Y-1004083D01*
X352517Y-1003500D01*
X352390Y-1002833D01*
Y-1002167D01*
X352517Y-1001500D01*
X352770Y-1000917D01*
X353150Y-1000417D01*
X353593Y-1000083D01*
X354100Y-1000000D01*
X354607Y-1000083D01*
X355050Y-1000417D01*
X355430Y-1000917D01*
X355683Y-1001500D01*
X355810Y-1002167D01*
Y-1002833D01*
X355683Y-1003500D01*
X355430Y-1004083D01*
X355050Y-1004583D01*
X354607Y-1004917D01*
X354100Y-1005000D01*
G01X357933Y-1004000D02*
X358250Y-1004500D01*
X358630Y-1004833D01*
X359073Y-1005000D01*
X359580Y-1004833D01*
X359960Y-1004500D01*
X360340Y-1004000D01*
X360467Y-1003333D01*
Y-1000000D01*
G01X365567Y-1005000D02*
X363033D01*
Y-1000000D01*
X365567D01*
G01X364553Y-1002417D02*
X363033D01*
G01X370793Y-1000417D02*
X370413Y-1000167D01*
X369970Y-1000000D01*
X369463D01*
X368893Y-1000250D01*
X368450Y-1000667D01*
X368133Y-1001167D01*
X367880Y-1002000D01*
X367817Y-1002750D01*
X367943Y-1003500D01*
X368133Y-1004000D01*
X368513Y-1004500D01*
X368957Y-1004833D01*
X369400Y-1005000D01*
X369843D01*
X370287Y-1004833D01*
X370667Y-1004583D01*
X370983Y-1004250D01*
G01X374500Y-1000000D02*
Y-1005000D01*
G01X373043Y-1000000D02*
X375957D01*
G01X379600Y-1005167D02*
X379473Y-1005083D01*
Y-1004917D01*
X379600Y-1004833D01*
X379727Y-1004917D01*
Y-1005083D01*
X379600Y-1005167D01*
G01Y-1002917D02*
X379473Y-1002833D01*
Y-1002667D01*
X379600Y-1002583D01*
X379727Y-1002667D01*
Y-1002833D01*
X379600Y-1002917D01*
G01X337000Y-1020000D02*
X537000D01*
G01X348425Y603543D02*
G03X328740Y623228I-19685J0D01*
G01D02*
X326772D01*
G01X356299Y435039D02*
G03X377952Y413386I21653J0D01*
G01X377953Y405512D02*
G02X348425Y435039I-1J29528D01*
G01X356299D02*
Y738607D01*
G01X348425Y435039D02*
Y603543D01*
G01Y591732D02*
G03X356299I3937J0D01*
G01X348425Y572046D02*
G02X356299I3937J0D01*
G01Y738607D02*
G03X348425Y746481I-7874J0D01*
G01X1354331Y413386D02*
X1154764D01*
G02X1146890Y421260I0J7874D01*
G01Y479449D01*
G03X1135079Y491260I-11811J0D01*
G01X550827D01*
G03X539016Y479449I0J-11811D01*
G01Y421260D01*
G02X531142Y413386I-7874J0D01*
G01X377952D01*
G01X1354331Y405512D02*
X377953D01*
G01X437008Y-683661D02*
G03X456693Y-663976I0J19685D01*
G01X452000Y-1045000D02*
Y-1070000D01*
G01X454633Y-1047500D02*
Y-1052500D01*
X457167D01*
G01X460240Y-1047500D02*
X461760D01*
G01X461000D02*
Y-1052500D01*
G01X460240D02*
X461760D01*
G01X466607Y-1049833D02*
X466860Y-1049583D01*
X467050Y-1049167D01*
X467177Y-1048583D01*
X467050Y-1048083D01*
X466797Y-1047750D01*
X466353Y-1047500D01*
X464643D01*
Y-1052500D01*
X466733D01*
X467177Y-1052167D01*
X467430Y-1051667D01*
X467557Y-1051083D01*
X467430Y-1050500D01*
X467050Y-1050000D01*
X466607Y-1049833D01*
X464643D01*
G01X471200Y-1052667D02*
X471073Y-1052583D01*
Y-1052417D01*
X471200Y-1052333D01*
X471327Y-1052417D01*
Y-1052583D01*
X471200Y-1052667D01*
G01Y-1050417D02*
X471073Y-1050333D01*
Y-1050167D01*
X471200Y-1050083D01*
X471327Y-1050167D01*
Y-1050333D01*
X471200Y-1050417D01*
G01X456693Y-642913D02*
G02X468504Y-631102I11811J0D01*
G01X456693Y-663976D02*
Y-642913D01*
G01X444704Y405512D02*
G03Y413386I0J3937D01*
G01X464390Y405512D02*
G02Y413386I0J3937D01*
G01X537047Y483386D02*
X466811D01*
G01X537047D02*
X466811D01*
G01X495000Y-1045000D02*
Y-1070000D01*
G01X498900Y-1047500D02*
Y-1052500D01*
G01X497443Y-1047500D02*
X500357D01*
G01X504000Y-1052500D02*
X503620Y-1052417D01*
X503240Y-1052083D01*
X502987Y-1051500D01*
X502860Y-1050833D01*
X502987Y-1050167D01*
X503240Y-1049583D01*
X503620Y-1049250D01*
X504000Y-1049167D01*
X504380Y-1049250D01*
X504760Y-1049583D01*
X505013Y-1050167D01*
X505077Y-1050833D01*
X505013Y-1051500D01*
X504760Y-1052083D01*
X504380Y-1052417D01*
X504000Y-1052500D01*
G01X509100D02*
X508720Y-1052417D01*
X508340Y-1052083D01*
X508087Y-1051500D01*
X507960Y-1050833D01*
X508087Y-1050167D01*
X508340Y-1049583D01*
X508720Y-1049250D01*
X509100Y-1049167D01*
X509480Y-1049250D01*
X509860Y-1049583D01*
X510113Y-1050167D01*
X510177Y-1050833D01*
X510113Y-1051500D01*
X509860Y-1052083D01*
X509480Y-1052417D01*
X509100Y-1052500D01*
G01X514200D02*
Y-1047500D01*
G01X519300Y-1052667D02*
X519173Y-1052583D01*
Y-1052417D01*
X519300Y-1052333D01*
X519427Y-1052417D01*
Y-1052583D01*
X519300Y-1052667D01*
G01Y-1050417D02*
X519173Y-1050333D01*
Y-1050167D01*
X519300Y-1050083D01*
X519427Y-1050167D01*
Y-1050333D01*
X519300Y-1050417D01*
G01X495000Y-1020000D02*
Y-1045000D01*
G01X497633Y-1027500D02*
Y-1022500D01*
X499217D01*
X499723Y-1022750D01*
X500040Y-1023083D01*
X500167Y-1023750D01*
X500040Y-1024417D01*
X499660Y-1024833D01*
X499217Y-1025083D01*
X497633D01*
G01X499217D02*
X500167Y-1027500D01*
G01X505267D02*
X502733D01*
Y-1022500D01*
X505267D01*
G01X504253Y-1024917D02*
X502733D01*
G01X507517Y-1022500D02*
X509100Y-1027500D01*
X510683Y-1022500D01*
G01X514200Y-1027667D02*
X514073Y-1027583D01*
Y-1027417D01*
X514200Y-1027333D01*
X514327Y-1027417D01*
Y-1027583D01*
X514200Y-1027667D01*
G01Y-1025417D02*
X514073Y-1025333D01*
Y-1025167D01*
X514200Y-1025083D01*
X514327Y-1025167D01*
Y-1025333D01*
X514200Y-1025417D01*
G01X490158Y-754355D02*
G03X498032Y-746481I0J7874D01*
G01D02*
Y-442913D01*
G01X470473Y-631102D02*
G03X490158Y-611417I0J19685D01*
G01X468504Y-631102D02*
X470473D01*
G01X490158Y-611417D02*
Y-442913D01*
G01X498032Y-579920D02*
G02X490158I-3937J0D01*
G01X498032Y-599606D02*
G03X490158I-3937J0D01*
G01X519685Y-421260D02*
G03X498032Y-442913I0J-21653D01*
G01X490158D02*
G02X519685Y-413386I29527J0D01*
G01X503013Y-1073167D02*
X503120Y-1073042D01*
X503200Y-1072833D01*
X503253Y-1072542D01*
X503200Y-1072292D01*
X503093Y-1072125D01*
X502907Y-1072000D01*
X502187D01*
Y-1074500D01*
X503067D01*
X503253Y-1074333D01*
X503360Y-1074083D01*
X503413Y-1073792D01*
X503360Y-1073500D01*
X503200Y-1073250D01*
X503013Y-1073167D01*
X502187D01*
G01X505480Y-1074500D02*
Y-1072833D01*
G01Y-1073125D02*
X505373Y-1072958D01*
X505213Y-1072875D01*
X505027Y-1072833D01*
X504840Y-1072917D01*
X504680Y-1073083D01*
X504573Y-1073333D01*
X504520Y-1073667D01*
X504573Y-1074000D01*
X504680Y-1074250D01*
X504840Y-1074417D01*
X505027Y-1074500D01*
X505213Y-1074458D01*
X505373Y-1074333D01*
X505480Y-1074167D01*
G01X506800Y-1074208D02*
X506933Y-1074375D01*
X507120Y-1074500D01*
X507280D01*
X507440Y-1074417D01*
X507547Y-1074292D01*
X507600Y-1074125D01*
X507573Y-1073875D01*
X507467Y-1073750D01*
X506987Y-1073500D01*
X506880Y-1073208D01*
X506933Y-1073000D01*
X507040Y-1072875D01*
X507200Y-1072833D01*
X507360Y-1072875D01*
X507520Y-1073000D01*
G01X509000Y-1073375D02*
X509853D01*
X509773Y-1073083D01*
X509640Y-1072917D01*
X509453Y-1072833D01*
X509267Y-1072875D01*
X509107Y-1073000D01*
X509000Y-1073292D01*
X508947Y-1073542D01*
Y-1073792D01*
X509000Y-1074042D01*
X509133Y-1074292D01*
X509293Y-1074458D01*
X509480Y-1074500D01*
X509667Y-1074417D01*
X509853Y-1074167D01*
G01X511120Y-1074500D02*
Y-1072000D01*
G01Y-1073250D02*
X511253Y-1073000D01*
X511413Y-1072875D01*
X511573Y-1072833D01*
X511813Y-1072917D01*
X511973Y-1073083D01*
X512080Y-1073375D01*
Y-1073708D01*
X512027Y-1074042D01*
X511920Y-1074292D01*
X511733Y-1074458D01*
X511573Y-1074500D01*
X511413Y-1074458D01*
X511253Y-1074333D01*
X511120Y-1074125D01*
G01X513800Y-1074500D02*
X513640Y-1074458D01*
X513480Y-1074292D01*
X513373Y-1074000D01*
X513320Y-1073667D01*
X513373Y-1073333D01*
X513480Y-1073042D01*
X513640Y-1072875D01*
X513800Y-1072833D01*
X513960Y-1072875D01*
X514120Y-1073042D01*
X514227Y-1073333D01*
X514253Y-1073667D01*
X514227Y-1074000D01*
X514120Y-1074292D01*
X513960Y-1074458D01*
X513800Y-1074500D01*
G01X516480D02*
Y-1072833D01*
G01Y-1073125D02*
X516373Y-1072958D01*
X516213Y-1072875D01*
X516027Y-1072833D01*
X515840Y-1072917D01*
X515680Y-1073083D01*
X515573Y-1073333D01*
X515520Y-1073667D01*
X515573Y-1074000D01*
X515680Y-1074250D01*
X515840Y-1074417D01*
X516027Y-1074500D01*
X516213Y-1074458D01*
X516373Y-1074333D01*
X516480Y-1074167D01*
G01X517827Y-1074500D02*
Y-1072833D01*
G01Y-1073167D02*
X517960Y-1073000D01*
X518093Y-1072875D01*
X518280Y-1072833D01*
X518413Y-1072875D01*
X518573Y-1073000D01*
G01X520880Y-1072000D02*
Y-1074500D01*
G01Y-1074125D02*
X520773Y-1074333D01*
X520613Y-1074458D01*
X520427Y-1074500D01*
X520213Y-1074417D01*
X520053Y-1074208D01*
X519947Y-1073958D01*
X519920Y-1073667D01*
X519947Y-1073375D01*
X520053Y-1073125D01*
X520213Y-1072917D01*
X520427Y-1072833D01*
X520613Y-1072875D01*
X520747Y-1072958D01*
X520880Y-1073125D01*
G01X524267Y-1074500D02*
Y-1072000D01*
X524933D01*
X525147Y-1072125D01*
X525280Y-1072292D01*
X525333Y-1072625D01*
X525280Y-1072958D01*
X525120Y-1073167D01*
X524933Y-1073292D01*
X524267D01*
G01X524933D02*
X525333Y-1074500D01*
G01X526600Y-1073375D02*
X527453D01*
X527373Y-1073083D01*
X527240Y-1072917D01*
X527053Y-1072833D01*
X526867Y-1072875D01*
X526707Y-1073000D01*
X526600Y-1073292D01*
X526547Y-1073542D01*
Y-1073792D01*
X526600Y-1074042D01*
X526733Y-1074292D01*
X526893Y-1074458D01*
X527080Y-1074500D01*
X527267Y-1074417D01*
X527453Y-1074167D01*
G01X528720Y-1072833D02*
X529200Y-1074500D01*
X529680Y-1072833D01*
G01X531400Y-1074583D02*
X531347Y-1074542D01*
Y-1074458D01*
X531400Y-1074417D01*
X531453Y-1074458D01*
Y-1074542D01*
X531400Y-1074583D01*
G01X533600Y-1074500D02*
X533787Y-1074458D01*
X534000Y-1074333D01*
X534133Y-1074125D01*
X534187Y-1073833D01*
X534133Y-1073542D01*
X533973Y-1073292D01*
X533733Y-1073167D01*
X533467D01*
X533307Y-1073083D01*
X533173Y-1072875D01*
X533120Y-1072583D01*
X533200Y-1072292D01*
X533387Y-1072083D01*
X533600Y-1072000D01*
X533813Y-1072083D01*
X534000Y-1072292D01*
X534080Y-1072583D01*
X534027Y-1072875D01*
X533893Y-1073083D01*
X533733Y-1073167D01*
X533467D01*
X533227Y-1073292D01*
X533067Y-1073542D01*
X533013Y-1073833D01*
X533067Y-1074125D01*
X533200Y-1074333D01*
X533413Y-1074458D01*
X533600Y-1074500D01*
G01X536013Y-1073167D02*
X536120Y-1073042D01*
X536200Y-1072833D01*
X536253Y-1072542D01*
X536200Y-1072292D01*
X536093Y-1072125D01*
X535907Y-1072000D01*
X535187D01*
Y-1074500D01*
X536067D01*
X536253Y-1074333D01*
X536360Y-1074083D01*
X536413Y-1073792D01*
X536360Y-1073500D01*
X536200Y-1073250D01*
X536013Y-1073167D01*
X535187D01*
G01X1496064Y-421260D02*
X519685D01*
G01Y-413386D02*
X1496063D01*
G01X544961Y-7874D02*
G03Y0I0J3937D01*
G01X601142Y413386D02*
X554764D01*
G02X546890Y421260I0J7874D01*
G01Y475512D01*
G02X554764Y483386I7874J0D01*
G01X601142D01*
G01X546890Y428701D02*
G03X539016I-3937J0D01*
G01X541772Y444449D02*
G03I-1575J0D01*
G01Y436575D02*
G03I-1575J0D01*
G01X546890Y468071D02*
G02X539016I-3937J0D01*
G01X541772Y452323D02*
G03I-1575J0D01*
G01Y460197D02*
G03I-1575J0D01*
G01X597890Y483386D02*
X554764D01*
G03X546890Y475512I0J-7874D01*
G01Y459764D01*
G01X597890Y483386D02*
X554764D01*
G03X546890Y475512I0J-7874D01*
G01Y459764D01*
G01Y493229D02*
Y578701D01*
G01Y493229D02*
Y578701D01*
G01X564647Y-7874D02*
G02Y0I0J3937D01*
G01X576418Y405512D02*
G03Y413386I0J3937D01*
G01Y405512D02*
G03Y413386I0J3937D01*
G01X609625Y-421260D02*
G03Y-413386I0J3937D01*
G01X601142Y483386D02*
X1131142D01*
Y413386D01*
X601142D01*
G01Y483386D02*
Y413386D01*
G01X596103Y405512D02*
G02Y413386I0J3937D01*
G01Y405512D02*
G02Y413386I0J3937D01*
G01X629311Y-421260D02*
G02Y-413386I0J3937D01*
G01X674117Y483386D02*
G03Y491260I0J3937D01*
G01X713487Y483386D02*
G02Y491260I0J3937D01*
G01X691440Y490079D02*
G03I-1575J0D01*
G01X683566D02*
G03I-1575J0D01*
G01X699314D02*
G03I-1575J0D01*
G01X707188D02*
G03I-1575J0D01*
G01X734961Y-7874D02*
G03Y0I0J3937D01*
G01X754685Y-421260D02*
G03Y-413386I0J3937D01*
G01X754647Y-7874D02*
G02Y0I0J3937D01*
G01X774371Y-421260D02*
G02Y-413386I0J3937D01*
G01X856299Y413386D02*
G02Y405512I0J-3937D01*
G01X875985Y413386D02*
G03Y405512I0J-3937D01*
G01X924961Y-7874D02*
G03Y0I0J3937D01*
G01X944647Y-7874D02*
G02Y0I0J3937D01*
G01X927750Y865050D02*
X923100D01*
Y877550D01*
X927750D01*
G01X974117Y483386D02*
G03Y491260I0J3937D01*
G01X983566Y490079D02*
G03I-1575J0D01*
G01X971150Y865050D02*
X975800D01*
Y877550D01*
X971150D01*
G01X998031Y-421260D02*
G03Y-413386I0J3937D01*
G01X1013487Y483386D02*
G02Y491260I0J3937D01*
G01X991440Y490079D02*
G03I-1575J0D01*
G01X999314D02*
G03I-1575J0D01*
G01X1007188D02*
G03I-1575J0D01*
G01X1007025Y883800D02*
X1874016D01*
G01X1017717Y-421260D02*
G02Y-413386I0J3937D01*
G01X1066142Y413386D02*
Y483386D01*
G01X1099645Y413386D02*
G02Y405512I0J-3937D01*
G01X1114961Y-7874D02*
G03Y0I0J3937D01*
G01X1134647Y-7874D02*
G02Y0I0J3937D01*
G01X1131142Y483386D02*
G02X1139016Y475512I0J-7874D01*
G01Y421260D01*
G02X1131142Y413386I-7874J0D01*
G01X1119331D02*
G03Y405512I0J-3937D01*
G01X1147284Y436575D02*
G03I-1575J0D01*
G01Y444449D02*
G03I-1575J0D01*
G01X1139016Y428701D02*
G02X1146890I3937J0D01*
G01X1147284Y460197D02*
G03I-1575J0D01*
G01Y452323D02*
G03I-1575J0D01*
G01X1139016Y468071D02*
G03X1146890I3937J0D01*
G01X1198031Y-421260D02*
G03Y-413386I0J3937D01*
G01X1217717Y-421260D02*
G02Y-413386I0J3937D01*
G01X1244705Y413386D02*
G02Y405512I0J-3937D01*
G01X1264391Y413386D02*
G03Y405512I0J-3937D01*
G01X1334647Y-7874D02*
G02Y0I0J3937D01*
G01X1314961Y-7874D02*
G03Y0I0J3937D01*
G01X1354331Y413386D02*
G03X1375984Y435039I0J21653D01*
G01X1383858D02*
G02X1354331Y405512I-29527J0D01*
G01X1375984Y738607D02*
Y435039D01*
G01X1383858Y603543D02*
Y435039D01*
G01X1375984Y591732D02*
G03X1383858I3937J0D01*
G01X1375984Y572046D02*
G02X1383858I3937J0D01*
G01X1417323Y635039D02*
G02X1405512Y623228I-11811J0D01*
G01D02*
X1403543D01*
G01D02*
G03X1383858Y603543I0J-19685D01*
G01Y746481D02*
G03X1375984Y738607I0J-7874D01*
G01X1620379Y746481D02*
X1383858D01*
G01X1409626Y-413386D02*
G02Y-421260I0J-3937D01*
G01X1429312Y-413386D02*
G03Y-421260I0J-3937D01*
G01X1437008Y675787D02*
G03X1417323Y656102I0J-19685D01*
G01D02*
Y635039D01*
G01X1590551Y675787D02*
X1437008D01*
G01X1517717Y-442913D02*
G03X1496064Y-421260I-21653J0D01*
G01X1496063Y-413386D02*
G02X1525591Y-442913I0J-29528D01*
G01X1517717D02*
Y-746481D01*
G01X1525591Y-754355D02*
X1762111D01*
G01X1517717Y-746481D02*
G03X1525591Y-754355I7874J0D01*
G01Y-611417D02*
G03X1545276Y-631102I19685J0D01*
G01X1525591Y-442913D02*
Y-611417D01*
G01Y-579920D02*
G02X1517717I-3937J0D01*
G01X1525591Y-599606D02*
G03X1517717I-3937J0D01*
G01X1547244Y-631102D02*
G02X1559055Y-642913I0J-11811D01*
G01X1545276Y-631102D02*
X1547244D01*
G01X1578740Y-683661D02*
X1732284D01*
G01X1559055Y-663976D02*
G03X1578740Y-683661I19685J0D01*
G01X1559055Y-642913D02*
Y-663976D01*
G01X1629921Y623228D02*
G02X1610236Y642913I0J19685D01*
G01D02*
Y656102D01*
G01D02*
G03X1590551Y675787I-19685J0D01*
G01X1628253Y642913D02*
G03X1640064Y631102I11811J0D01*
G01D02*
X1712598D01*
G01Y623228D02*
X1629921D01*
G01X1628253Y642913D02*
Y738607D01*
G01D02*
G03X1620379Y746481I-7874J0D01*
G01X1681103Y631102D02*
G03Y623228I0J-3937D01*
G01X1661417Y631102D02*
G02Y623228I0J-3937D01*
G01X1692912Y-7874D02*
G03Y0I0J3937D01*
G01X1732284Y-683661D02*
G03X1751969Y-663976I0J19685D01*
G01X1712598Y-7874D02*
G02Y0I0J3937D01*
G01D02*
G03X1732283Y19685I0J19685D01*
G01D02*
Y46339D01*
G01D02*
G02X1751969Y66024I19685J-1D01*
G01Y518780D02*
G02X1732283Y538465I0J19685D01*
G01D02*
Y603543D01*
G01X1740157Y561161D02*
G03X1732283I-3937J0D01*
G01X1740157Y580847D02*
G02X1732283I-3937J0D01*
G01X1712598Y631102D02*
G02X1740157Y603543I0J-27559D01*
G01X1732283D02*
G03X1712598Y623228I-19685J0D01*
G01X1762111Y-754355D02*
G03X1769985Y-746481I0J7874D01*
G01X1751969Y-650787D02*
G02X1771654Y-631102I19685J0D01*
G01X1751969Y-663976D02*
Y-650787D01*
G01Y66024D02*
X1854331D01*
G01X1740157Y603543D02*
Y538465D01*
G01D02*
G03X1751968Y526654I11812J0D01*
G01D02*
X1866142D01*
G03X1874016Y534528I0J7874D01*
G01Y734851D01*
G01X1854331Y518780D02*
X1751969D01*
G01X1769985Y-746481D02*
Y-650787D01*
G01X1781796Y-638976D02*
G03X1769985Y-650787I0J-11811D01*
G01X1874016Y-702914D02*
Y-646850D01*
G03X1866142Y-638976I-7874J0D01*
G01X1781796D01*
G01X1771654Y-631102D02*
X1854331D01*
G01X1790562Y785851D02*
X1976200D01*
G01X1828799Y-793725D02*
X1976200D01*
G01X1803149Y-631102D02*
G02Y-638976I0J-3937D01*
G01X1822835Y-631102D02*
G03Y-638976I0J-3937D01*
G01X1822834Y526654D02*
G02Y518780I0J-3937D01*
G01X1866142Y-793725D02*
X1842520D01*
G01X1854331Y-631102D02*
G03X1874016Y-611417I0J19685D01*
G01Y-27559D02*
G03X1854331Y-7874I-19685J0D01*
G01Y66024D02*
G03X1874016Y85709I0J19685D01*
G01Y499094D02*
G03X1854331Y518780I-19685J1D01*
G01X1842520Y526654D02*
G03Y518780I0J-3937D01*
G01X1866142Y785851D02*
X1842520D01*
G01X1874016Y-702914D02*
Y-785851D01*
G02X1866142Y-793725I-7874J0D01*
G01X1883859D02*
X1923646D01*
G01X1874016Y-611417D02*
Y-27559D01*
G01Y85709D02*
Y499094D01*
G01Y709516D02*
Y884800D01*
G01Y734851D02*
Y777977D01*
G03X1866142Y785851I-7874J0D01*
G01X1874016Y795694D02*
Y865930D01*
G01X1883859Y785851D02*
X1969331D01*
G01X1869016Y882800D02*
X1874016Y883800D01*
X1869016Y884800D01*
Y882800D01*
G01X1975200Y-32825D02*
Y-793725D01*
G01X1974200Y-788725D02*
X1975200Y-793725D01*
X1976200Y-788725D01*
X1974200D01*
G01X1975200Y82625D02*
Y785851D01*
G01X1976200Y780851D02*
X1975200Y785851D01*
X1974200Y780851D01*
X1976200D01*
G01X1993950Y-15250D02*
Y-19900D01*
X1981450D01*
Y-15250D01*
G01X1993950Y65350D02*
Y70000D01*
X1981450D01*
Y65350D01*
G01X2162635Y-589061D02*
X2162888Y-588811D01*
X2163078Y-588395D01*
X2163205Y-587811D01*
X2163078Y-587311D01*
X2162825Y-586978D01*
X2162381Y-586728D01*
X2160671D01*
Y-591728D01*
X2162761D01*
X2163205Y-591395D01*
X2163458Y-590895D01*
X2163585Y-590311D01*
X2163458Y-589728D01*
X2163078Y-589228D01*
X2162635Y-589061D01*
X2160671D01*
G01X2166341Y-591728D02*
Y-588395D01*
G01Y-589061D02*
X2166658Y-588728D01*
X2166975Y-588478D01*
X2167418Y-588395D01*
X2167735Y-588478D01*
X2168115Y-588728D01*
G01X2171378Y-589478D02*
X2173405D01*
X2173215Y-588895D01*
X2172898Y-588561D01*
X2172455Y-588395D01*
X2172011Y-588478D01*
X2171631Y-588728D01*
X2171378Y-589311D01*
X2171251Y-589811D01*
Y-590311D01*
X2171378Y-590811D01*
X2171695Y-591311D01*
X2172075Y-591645D01*
X2172518Y-591728D01*
X2172961Y-591561D01*
X2173405Y-591061D01*
G01X2178568Y-591728D02*
Y-588395D01*
G01Y-588978D02*
X2178315Y-588645D01*
X2177935Y-588478D01*
X2177491Y-588395D01*
X2177048Y-588561D01*
X2176668Y-588895D01*
X2176415Y-589395D01*
X2176288Y-590061D01*
X2176415Y-590728D01*
X2176668Y-591228D01*
X2177048Y-591561D01*
X2177491Y-591728D01*
X2177935Y-591645D01*
X2178315Y-591395D01*
X2178568Y-591061D01*
G01X2181451Y-591728D02*
Y-586728D01*
G01X2183478Y-588395D02*
X2181451Y-590311D01*
G01X2182275Y-589561D02*
X2183605Y-591728D01*
G01X2187628Y-586728D02*
Y-591728D01*
G01X2186741Y-588395D02*
X2188515D01*
G01X2193868Y-591728D02*
Y-588395D01*
G01Y-588978D02*
X2193615Y-588645D01*
X2193235Y-588478D01*
X2192791Y-588395D01*
X2192348Y-588561D01*
X2191968Y-588895D01*
X2191715Y-589395D01*
X2191588Y-590061D01*
X2191715Y-590728D01*
X2191968Y-591228D01*
X2192348Y-591561D01*
X2192791Y-591728D01*
X2193235Y-591645D01*
X2193615Y-591395D01*
X2193868Y-591061D01*
G01X2196688Y-591728D02*
Y-586728D01*
G01Y-589228D02*
X2197005Y-588728D01*
X2197385Y-588478D01*
X2197765Y-588395D01*
X2198335Y-588561D01*
X2198715Y-588895D01*
X2198968Y-589478D01*
Y-590145D01*
X2198841Y-590811D01*
X2198588Y-591311D01*
X2198145Y-591645D01*
X2197765Y-591728D01*
X2197385Y-591645D01*
X2197005Y-591395D01*
X2196688Y-590978D01*
G01X2202928Y-591895D02*
X2202801Y-591811D01*
Y-591645D01*
X2202928Y-591561D01*
X2203055Y-591645D01*
Y-591811D01*
X2202928Y-591895D01*
G01Y-589645D02*
X2202801Y-589561D01*
Y-589395D01*
X2202928Y-589311D01*
X2203055Y-589395D01*
Y-589561D01*
X2202928Y-589645D01*
G01X2237425Y-525198D02*
Y-520198D01*
X2239831D01*
G01X2238945Y-522615D02*
X2237425D01*
G01X2243728Y-525198D02*
X2243348Y-525115D01*
X2242968Y-524781D01*
X2242715Y-524198D01*
X2242588Y-523531D01*
X2242715Y-522865D01*
X2242968Y-522281D01*
X2243348Y-521948D01*
X2243728Y-521865D01*
X2244108Y-521948D01*
X2244488Y-522281D01*
X2244741Y-522865D01*
X2244805Y-523531D01*
X2244741Y-524198D01*
X2244488Y-524781D01*
X2244108Y-525115D01*
X2243728Y-525198D01*
G01X2247941D02*
Y-521865D01*
G01Y-522531D02*
X2248258Y-522198D01*
X2248575Y-521948D01*
X2249018Y-521865D01*
X2249335Y-521948D01*
X2249715Y-522198D01*
G01X2257761Y-525198D02*
Y-520198D01*
X2259281D01*
X2259788Y-520448D01*
X2260168Y-521031D01*
X2260295Y-521698D01*
X2260168Y-522365D01*
X2259851Y-522865D01*
X2259281Y-523115D01*
X2257761D01*
G01X2265268Y-525198D02*
Y-521865D01*
G01Y-522448D02*
X2265015Y-522115D01*
X2264635Y-521948D01*
X2264191Y-521865D01*
X2263748Y-522031D01*
X2263368Y-522365D01*
X2263115Y-522865D01*
X2262988Y-523531D01*
X2263115Y-524198D01*
X2263368Y-524698D01*
X2263748Y-525031D01*
X2264191Y-525198D01*
X2264635Y-525115D01*
X2265015Y-524865D01*
X2265268Y-524531D01*
G01X2268151Y-525198D02*
Y-521865D01*
G01Y-522698D02*
X2268405Y-522281D01*
X2268785Y-521948D01*
X2269291Y-521865D01*
X2269735Y-521948D01*
X2270115Y-522281D01*
X2270305Y-522865D01*
Y-525198D01*
G01X2273378Y-522948D02*
X2275405D01*
X2275215Y-522365D01*
X2274898Y-522031D01*
X2274455Y-521865D01*
X2274011Y-521948D01*
X2273631Y-522198D01*
X2273378Y-522781D01*
X2273251Y-523281D01*
Y-523781D01*
X2273378Y-524281D01*
X2273695Y-524781D01*
X2274075Y-525115D01*
X2274518Y-525198D01*
X2274961Y-525031D01*
X2275405Y-524531D01*
G01X2279428Y-525198D02*
Y-520198D01*
G01X2290135Y-522531D02*
X2290388Y-522281D01*
X2290578Y-521865D01*
X2290705Y-521281D01*
X2290578Y-520781D01*
X2290325Y-520448D01*
X2289881Y-520198D01*
X2288171D01*
Y-525198D01*
X2290261D01*
X2290705Y-524865D01*
X2290958Y-524365D01*
X2291085Y-523781D01*
X2290958Y-523198D01*
X2290578Y-522698D01*
X2290135Y-522531D01*
X2288171D01*
G01X2294728Y-525198D02*
X2294348Y-525115D01*
X2293968Y-524781D01*
X2293715Y-524198D01*
X2293588Y-523531D01*
X2293715Y-522865D01*
X2293968Y-522281D01*
X2294348Y-521948D01*
X2294728Y-521865D01*
X2295108Y-521948D01*
X2295488Y-522281D01*
X2295741Y-522865D01*
X2295805Y-523531D01*
X2295741Y-524198D01*
X2295488Y-524781D01*
X2295108Y-525115D01*
X2294728Y-525198D01*
G01X2300968D02*
Y-521865D01*
G01Y-522448D02*
X2300715Y-522115D01*
X2300335Y-521948D01*
X2299891Y-521865D01*
X2299448Y-522031D01*
X2299068Y-522365D01*
X2298815Y-522865D01*
X2298688Y-523531D01*
X2298815Y-524198D01*
X2299068Y-524698D01*
X2299448Y-525031D01*
X2299891Y-525198D01*
X2300335Y-525115D01*
X2300715Y-524865D01*
X2300968Y-524531D01*
G01X2304041Y-525198D02*
Y-521865D01*
G01Y-522531D02*
X2304358Y-522198D01*
X2304675Y-521948D01*
X2305118Y-521865D01*
X2305435Y-521948D01*
X2305815Y-522198D01*
G01X2311168Y-520198D02*
Y-525198D01*
G01Y-524448D02*
X2310915Y-524865D01*
X2310535Y-525115D01*
X2310091Y-525198D01*
X2309585Y-525031D01*
X2309205Y-524615D01*
X2308951Y-524115D01*
X2308888Y-523531D01*
X2308951Y-522948D01*
X2309205Y-522448D01*
X2309585Y-522031D01*
X2310091Y-521865D01*
X2310535Y-521948D01*
X2310851Y-522115D01*
X2311168Y-522448D01*
G01X2237425Y-525198D02*
Y-520198D01*
X2239831D01*
G01X2238945Y-522615D02*
X2237425D01*
G01X2243728Y-525198D02*
X2243348Y-525115D01*
X2242968Y-524781D01*
X2242715Y-524198D01*
X2242588Y-523531D01*
X2242715Y-522865D01*
X2242968Y-522281D01*
X2243348Y-521948D01*
X2243728Y-521865D01*
X2244108Y-521948D01*
X2244488Y-522281D01*
X2244741Y-522865D01*
X2244805Y-523531D01*
X2244741Y-524198D01*
X2244488Y-524781D01*
X2244108Y-525115D01*
X2243728Y-525198D01*
G01X2247941D02*
Y-521865D01*
G01Y-522531D02*
X2248258Y-522198D01*
X2248575Y-521948D01*
X2249018Y-521865D01*
X2249335Y-521948D01*
X2249715Y-522198D01*
G01X2257761Y-525198D02*
Y-520198D01*
X2259281D01*
X2259788Y-520448D01*
X2260168Y-521031D01*
X2260295Y-521698D01*
X2260168Y-522365D01*
X2259851Y-522865D01*
X2259281Y-523115D01*
X2257761D01*
G01X2265268Y-525198D02*
Y-521865D01*
G01Y-522448D02*
X2265015Y-522115D01*
X2264635Y-521948D01*
X2264191Y-521865D01*
X2263748Y-522031D01*
X2263368Y-522365D01*
X2263115Y-522865D01*
X2262988Y-523531D01*
X2263115Y-524198D01*
X2263368Y-524698D01*
X2263748Y-525031D01*
X2264191Y-525198D01*
X2264635Y-525115D01*
X2265015Y-524865D01*
X2265268Y-524531D01*
G01X2268151Y-525198D02*
Y-521865D01*
G01Y-522698D02*
X2268405Y-522281D01*
X2268785Y-521948D01*
X2269291Y-521865D01*
X2269735Y-521948D01*
X2270115Y-522281D01*
X2270305Y-522865D01*
Y-525198D01*
G01X2273378Y-522948D02*
X2275405D01*
X2275215Y-522365D01*
X2274898Y-522031D01*
X2274455Y-521865D01*
X2274011Y-521948D01*
X2273631Y-522198D01*
X2273378Y-522781D01*
X2273251Y-523281D01*
Y-523781D01*
X2273378Y-524281D01*
X2273695Y-524781D01*
X2274075Y-525115D01*
X2274518Y-525198D01*
X2274961Y-525031D01*
X2275405Y-524531D01*
G01X2279428Y-525198D02*
Y-520198D01*
G01X2290135Y-522531D02*
X2290388Y-522281D01*
X2290578Y-521865D01*
X2290705Y-521281D01*
X2290578Y-520781D01*
X2290325Y-520448D01*
X2289881Y-520198D01*
X2288171D01*
Y-525198D01*
X2290261D01*
X2290705Y-524865D01*
X2290958Y-524365D01*
X2291085Y-523781D01*
X2290958Y-523198D01*
X2290578Y-522698D01*
X2290135Y-522531D01*
X2288171D01*
G01X2294728Y-525198D02*
X2294348Y-525115D01*
X2293968Y-524781D01*
X2293715Y-524198D01*
X2293588Y-523531D01*
X2293715Y-522865D01*
X2293968Y-522281D01*
X2294348Y-521948D01*
X2294728Y-521865D01*
X2295108Y-521948D01*
X2295488Y-522281D01*
X2295741Y-522865D01*
X2295805Y-523531D01*
X2295741Y-524198D01*
X2295488Y-524781D01*
X2295108Y-525115D01*
X2294728Y-525198D01*
G01X2300968D02*
Y-521865D01*
G01Y-522448D02*
X2300715Y-522115D01*
X2300335Y-521948D01*
X2299891Y-521865D01*
X2299448Y-522031D01*
X2299068Y-522365D01*
X2298815Y-522865D01*
X2298688Y-523531D01*
X2298815Y-524198D01*
X2299068Y-524698D01*
X2299448Y-525031D01*
X2299891Y-525198D01*
X2300335Y-525115D01*
X2300715Y-524865D01*
X2300968Y-524531D01*
G01X2304041Y-525198D02*
Y-521865D01*
G01Y-522531D02*
X2304358Y-522198D01*
X2304675Y-521948D01*
X2305118Y-521865D01*
X2305435Y-521948D01*
X2305815Y-522198D01*
G01X2311168Y-520198D02*
Y-525198D01*
G01Y-524448D02*
X2310915Y-524865D01*
X2310535Y-525115D01*
X2310091Y-525198D01*
X2309585Y-525031D01*
X2309205Y-524615D01*
X2308951Y-524115D01*
X2308888Y-523531D01*
X2308951Y-522948D01*
X2309205Y-522448D01*
X2309585Y-522031D01*
X2310091Y-521865D01*
X2310535Y-521948D01*
X2310851Y-522115D01*
X2311168Y-522448D01*
G01X2160925Y-487398D02*
Y-482398D01*
X2163331D01*
G01X2162445Y-484815D02*
X2160925D01*
G01X2167228Y-484065D02*
Y-487398D01*
G01Y-482731D02*
X2167101Y-482648D01*
Y-482481D01*
X2167228Y-482398D01*
X2167355Y-482481D01*
Y-482648D01*
X2167228Y-482731D01*
G01X2173468Y-482398D02*
Y-487398D01*
G01Y-486648D02*
X2173215Y-487065D01*
X2172835Y-487315D01*
X2172391Y-487398D01*
X2171885Y-487231D01*
X2171505Y-486815D01*
X2171251Y-486315D01*
X2171188Y-485731D01*
X2171251Y-485148D01*
X2171505Y-484648D01*
X2171885Y-484231D01*
X2172391Y-484065D01*
X2172835Y-484148D01*
X2173151Y-484315D01*
X2173468Y-484648D01*
G01X2176351Y-484065D02*
Y-486398D01*
X2176605Y-486981D01*
X2176985Y-487315D01*
X2177428Y-487398D01*
X2177871Y-487315D01*
X2178251Y-486981D01*
X2178505Y-486398D01*
G01Y-487398D02*
Y-484065D01*
G01X2183541Y-484481D02*
X2183098Y-484148D01*
X2182718Y-484065D01*
X2182211Y-484231D01*
X2181831Y-484565D01*
X2181578Y-485148D01*
X2181515Y-485731D01*
X2181578Y-486315D01*
X2181831Y-486815D01*
X2182211Y-487231D01*
X2182718Y-487398D01*
X2183161Y-487231D01*
X2183541Y-486898D01*
G01X2187628Y-484065D02*
Y-487398D01*
G01Y-482731D02*
X2187501Y-482648D01*
Y-482481D01*
X2187628Y-482398D01*
X2187755Y-482481D01*
Y-482648D01*
X2187628Y-482731D01*
G01X2193868Y-487398D02*
Y-484065D01*
G01Y-484648D02*
X2193615Y-484315D01*
X2193235Y-484148D01*
X2192791Y-484065D01*
X2192348Y-484231D01*
X2191968Y-484565D01*
X2191715Y-485065D01*
X2191588Y-485731D01*
X2191715Y-486398D01*
X2191968Y-486898D01*
X2192348Y-487231D01*
X2192791Y-487398D01*
X2193235Y-487315D01*
X2193615Y-487065D01*
X2193868Y-486731D01*
G01X2197828Y-487398D02*
Y-482398D01*
G01X2206381Y-487398D02*
Y-482398D01*
X2208028Y-486565D01*
X2209675Y-482398D01*
Y-487398D01*
G01X2214268D02*
Y-484065D01*
G01Y-484648D02*
X2214015Y-484315D01*
X2213635Y-484148D01*
X2213191Y-484065D01*
X2212748Y-484231D01*
X2212368Y-484565D01*
X2212115Y-485065D01*
X2211988Y-485731D01*
X2212115Y-486398D01*
X2212368Y-486898D01*
X2212748Y-487231D01*
X2213191Y-487398D01*
X2213635Y-487315D01*
X2214015Y-487065D01*
X2214268Y-486731D01*
G01X2217341Y-487398D02*
Y-484065D01*
G01Y-484731D02*
X2217658Y-484398D01*
X2217975Y-484148D01*
X2218418Y-484065D01*
X2218735Y-484148D01*
X2219115Y-484398D01*
G01X2222251Y-487398D02*
Y-482398D01*
G01X2224278Y-484065D02*
X2222251Y-485981D01*
G01X2223075Y-485231D02*
X2224405Y-487398D01*
G01X2228428Y-487565D02*
X2228301Y-487481D01*
Y-487315D01*
X2228428Y-487231D01*
X2228555Y-487315D01*
Y-487481D01*
X2228428Y-487565D01*
G01Y-485315D02*
X2228301Y-485231D01*
Y-485065D01*
X2228428Y-484981D01*
X2228555Y-485065D01*
Y-485231D01*
X2228428Y-485315D01*
G01X2237235Y-487398D02*
Y-482398D01*
X2238501D01*
X2239008Y-482648D01*
X2239388Y-482981D01*
X2239705Y-483481D01*
X2239958Y-484065D01*
X2240021Y-484898D01*
X2239958Y-485731D01*
X2239705Y-486315D01*
X2239388Y-486815D01*
X2239008Y-487148D01*
X2238501Y-487398D01*
X2237235D01*
G01X2243728Y-484065D02*
Y-487398D01*
G01Y-482731D02*
X2243601Y-482648D01*
Y-482481D01*
X2243728Y-482398D01*
X2243855Y-482481D01*
Y-482648D01*
X2243728Y-482731D01*
G01X2249968Y-487398D02*
Y-484065D01*
G01Y-484648D02*
X2249715Y-484315D01*
X2249335Y-484148D01*
X2248891Y-484065D01*
X2248448Y-484231D01*
X2248068Y-484565D01*
X2247815Y-485065D01*
X2247688Y-485731D01*
X2247815Y-486398D01*
X2248068Y-486898D01*
X2248448Y-487231D01*
X2248891Y-487398D01*
X2249335Y-487315D01*
X2249715Y-487065D01*
X2249968Y-486731D01*
G01X2252028Y-487398D02*
Y-484065D01*
G01Y-484981D02*
X2252218Y-484565D01*
X2252535Y-484231D01*
X2252978Y-484065D01*
X2253421Y-484231D01*
X2253738Y-484565D01*
X2253928Y-484981D01*
Y-487398D01*
G01Y-484981D02*
X2254118Y-484565D01*
X2254435Y-484231D01*
X2254878Y-484065D01*
X2255321Y-484231D01*
X2255638Y-484565D01*
X2255828Y-485065D01*
Y-487398D01*
G01X2258078Y-485148D02*
X2260105D01*
X2259915Y-484565D01*
X2259598Y-484231D01*
X2259155Y-484065D01*
X2258711Y-484148D01*
X2258331Y-484398D01*
X2258078Y-484981D01*
X2257951Y-485481D01*
Y-485981D01*
X2258078Y-486481D01*
X2258395Y-486981D01*
X2258775Y-487315D01*
X2259218Y-487398D01*
X2259661Y-487231D01*
X2260105Y-486731D01*
G01X2264128Y-482398D02*
Y-487398D01*
G01X2263241Y-484065D02*
X2265015D01*
G01X2268278Y-485148D02*
X2270305D01*
X2270115Y-484565D01*
X2269798Y-484231D01*
X2269355Y-484065D01*
X2268911Y-484148D01*
X2268531Y-484398D01*
X2268278Y-484981D01*
X2268151Y-485481D01*
Y-485981D01*
X2268278Y-486481D01*
X2268595Y-486981D01*
X2268975Y-487315D01*
X2269418Y-487398D01*
X2269861Y-487231D01*
X2270305Y-486731D01*
G01X2273441Y-487398D02*
Y-484065D01*
G01Y-484731D02*
X2273758Y-484398D01*
X2274075Y-484148D01*
X2274518Y-484065D01*
X2274835Y-484148D01*
X2275215Y-484398D01*
G01X2284528Y-487398D02*
Y-482398D01*
X2283768Y-483398D01*
G01Y-487398D02*
X2285288D01*
G01X2287728D02*
Y-484065D01*
G01Y-484981D02*
X2287918Y-484565D01*
X2288235Y-484231D01*
X2288678Y-484065D01*
X2289121Y-484231D01*
X2289438Y-484565D01*
X2289628Y-484981D01*
Y-487398D01*
G01Y-484981D02*
X2289818Y-484565D01*
X2290135Y-484231D01*
X2290578Y-484065D01*
X2291021Y-484231D01*
X2291338Y-484565D01*
X2291528Y-485065D01*
Y-487398D01*
G01X2292828D02*
Y-484065D01*
G01Y-484981D02*
X2293018Y-484565D01*
X2293335Y-484231D01*
X2293778Y-484065D01*
X2294221Y-484231D01*
X2294538Y-484565D01*
X2294728Y-484981D01*
Y-487398D01*
G01Y-484981D02*
X2294918Y-484565D01*
X2295235Y-484231D01*
X2295678Y-484065D01*
X2296121Y-484231D01*
X2296438Y-484565D01*
X2296628Y-485065D01*
Y-487398D01*
G01X2306321Y-482815D02*
X2305941Y-482565D01*
X2305498Y-482398D01*
X2304991D01*
X2304421Y-482648D01*
X2303978Y-483065D01*
X2303661Y-483565D01*
X2303408Y-484398D01*
X2303345Y-485148D01*
X2303471Y-485898D01*
X2303661Y-486398D01*
X2304041Y-486898D01*
X2304485Y-487231D01*
X2304928Y-487398D01*
X2305371D01*
X2305815Y-487231D01*
X2306195Y-486981D01*
X2306511Y-486648D01*
G01X2310028Y-487398D02*
X2309648Y-487315D01*
X2309268Y-486981D01*
X2309015Y-486398D01*
X2308888Y-485731D01*
X2309015Y-485065D01*
X2309268Y-484481D01*
X2309648Y-484148D01*
X2310028Y-484065D01*
X2310408Y-484148D01*
X2310788Y-484481D01*
X2311041Y-485065D01*
X2311105Y-485731D01*
X2311041Y-486398D01*
X2310788Y-486981D01*
X2310408Y-487315D01*
X2310028Y-487398D01*
G01X2313988Y-489065D02*
Y-484065D01*
G01Y-484815D02*
X2314305Y-484398D01*
X2314621Y-484148D01*
X2315128Y-484065D01*
X2315571Y-484148D01*
X2316015Y-484565D01*
X2316205Y-485148D01*
X2316268Y-485731D01*
X2316205Y-486315D01*
X2316015Y-486898D01*
X2315635Y-487231D01*
X2315128Y-487398D01*
X2314685Y-487315D01*
X2314241Y-487065D01*
X2313988Y-486731D01*
G01X2319088Y-489065D02*
Y-484065D01*
G01Y-484815D02*
X2319405Y-484398D01*
X2319721Y-484148D01*
X2320228Y-484065D01*
X2320671Y-484148D01*
X2321115Y-484565D01*
X2321305Y-485148D01*
X2321368Y-485731D01*
X2321305Y-486315D01*
X2321115Y-486898D01*
X2320735Y-487231D01*
X2320228Y-487398D01*
X2319785Y-487315D01*
X2319341Y-487065D01*
X2319088Y-486731D01*
G01X2324378Y-485148D02*
X2326405D01*
X2326215Y-484565D01*
X2325898Y-484231D01*
X2325455Y-484065D01*
X2325011Y-484148D01*
X2324631Y-484398D01*
X2324378Y-484981D01*
X2324251Y-485481D01*
Y-485981D01*
X2324378Y-486481D01*
X2324695Y-486981D01*
X2325075Y-487315D01*
X2325518Y-487398D01*
X2325961Y-487231D01*
X2326405Y-486731D01*
G01X2329541Y-487398D02*
Y-484065D01*
G01Y-484731D02*
X2329858Y-484398D01*
X2330175Y-484148D01*
X2330618Y-484065D01*
X2330935Y-484148D01*
X2331315Y-484398D01*
G01X2237235Y-499998D02*
Y-494998D01*
X2238501D01*
X2239008Y-495248D01*
X2239388Y-495581D01*
X2239705Y-496081D01*
X2239958Y-496665D01*
X2240021Y-497498D01*
X2239958Y-498331D01*
X2239705Y-498915D01*
X2239388Y-499415D01*
X2239008Y-499748D01*
X2238501Y-499998D01*
X2237235D01*
G01X2243728Y-496665D02*
Y-499998D01*
G01Y-495331D02*
X2243601Y-495248D01*
Y-495081D01*
X2243728Y-494998D01*
X2243855Y-495081D01*
Y-495248D01*
X2243728Y-495331D01*
G01X2249968Y-499998D02*
Y-496665D01*
G01Y-497248D02*
X2249715Y-496915D01*
X2249335Y-496748D01*
X2248891Y-496665D01*
X2248448Y-496831D01*
X2248068Y-497165D01*
X2247815Y-497665D01*
X2247688Y-498331D01*
X2247815Y-498998D01*
X2248068Y-499498D01*
X2248448Y-499831D01*
X2248891Y-499998D01*
X2249335Y-499915D01*
X2249715Y-499665D01*
X2249968Y-499331D01*
G01X2252028Y-499998D02*
Y-496665D01*
G01Y-497581D02*
X2252218Y-497165D01*
X2252535Y-496831D01*
X2252978Y-496665D01*
X2253421Y-496831D01*
X2253738Y-497165D01*
X2253928Y-497581D01*
Y-499998D01*
G01Y-497581D02*
X2254118Y-497165D01*
X2254435Y-496831D01*
X2254878Y-496665D01*
X2255321Y-496831D01*
X2255638Y-497165D01*
X2255828Y-497665D01*
Y-499998D01*
G01X2258078Y-497748D02*
X2260105D01*
X2259915Y-497165D01*
X2259598Y-496831D01*
X2259155Y-496665D01*
X2258711Y-496748D01*
X2258331Y-496998D01*
X2258078Y-497581D01*
X2257951Y-498081D01*
Y-498581D01*
X2258078Y-499081D01*
X2258395Y-499581D01*
X2258775Y-499915D01*
X2259218Y-499998D01*
X2259661Y-499831D01*
X2260105Y-499331D01*
G01X2264128Y-494998D02*
Y-499998D01*
G01X2263241Y-496665D02*
X2265015D01*
G01X2268278Y-497748D02*
X2270305D01*
X2270115Y-497165D01*
X2269798Y-496831D01*
X2269355Y-496665D01*
X2268911Y-496748D01*
X2268531Y-496998D01*
X2268278Y-497581D01*
X2268151Y-498081D01*
Y-498581D01*
X2268278Y-499081D01*
X2268595Y-499581D01*
X2268975Y-499915D01*
X2269418Y-499998D01*
X2269861Y-499831D01*
X2270305Y-499331D01*
G01X2273441Y-499998D02*
Y-496665D01*
G01Y-497331D02*
X2273758Y-496998D01*
X2274075Y-496748D01*
X2274518Y-496665D01*
X2274835Y-496748D01*
X2275215Y-496998D01*
G01X2283135Y-498998D02*
X2283515Y-499581D01*
X2284021Y-499915D01*
X2284591Y-499998D01*
X2285098Y-499915D01*
X2285605Y-499498D01*
X2285921Y-498998D01*
X2285985Y-498498D01*
X2285858Y-497915D01*
X2285415Y-497498D01*
X2284971Y-497331D01*
X2284401D01*
G01X2284971D02*
X2285351Y-497081D01*
X2285668Y-496665D01*
X2285795Y-496165D01*
X2285668Y-495665D01*
X2285351Y-495248D01*
X2284781Y-494998D01*
X2284211Y-495081D01*
X2283641Y-495415D01*
G01X2287728Y-499998D02*
Y-496665D01*
G01Y-497581D02*
X2287918Y-497165D01*
X2288235Y-496831D01*
X2288678Y-496665D01*
X2289121Y-496831D01*
X2289438Y-497165D01*
X2289628Y-497581D01*
Y-499998D01*
G01Y-497581D02*
X2289818Y-497165D01*
X2290135Y-496831D01*
X2290578Y-496665D01*
X2291021Y-496831D01*
X2291338Y-497165D01*
X2291528Y-497665D01*
Y-499998D01*
G01X2292828D02*
Y-496665D01*
G01Y-497581D02*
X2293018Y-497165D01*
X2293335Y-496831D01*
X2293778Y-496665D01*
X2294221Y-496831D01*
X2294538Y-497165D01*
X2294728Y-497581D01*
Y-499998D01*
G01Y-497581D02*
X2294918Y-497165D01*
X2295235Y-496831D01*
X2295678Y-496665D01*
X2296121Y-496831D01*
X2296438Y-497165D01*
X2296628Y-497665D01*
Y-499998D01*
G01X2303598Y-499331D02*
X2304105Y-499748D01*
X2304675Y-499998D01*
X2305181D01*
X2305688Y-499748D01*
X2306068Y-499331D01*
X2306258Y-498748D01*
X2306131Y-498165D01*
X2305815Y-497665D01*
X2305245Y-497331D01*
X2304485Y-497165D01*
X2304041Y-496831D01*
X2303851Y-496248D01*
X2303978Y-495665D01*
X2304295Y-495248D01*
X2304738Y-494998D01*
X2305181D01*
X2305625Y-495165D01*
X2306005Y-495581D01*
G01X2310028Y-499998D02*
X2309648Y-499915D01*
X2309268Y-499581D01*
X2309015Y-498998D01*
X2308888Y-498331D01*
X2309015Y-497665D01*
X2309268Y-497081D01*
X2309648Y-496748D01*
X2310028Y-496665D01*
X2310408Y-496748D01*
X2310788Y-497081D01*
X2311041Y-497665D01*
X2311105Y-498331D01*
X2311041Y-498998D01*
X2310788Y-499581D01*
X2310408Y-499915D01*
X2310028Y-499998D01*
G01X2315128D02*
Y-494998D01*
G01X2321368D02*
Y-499998D01*
G01Y-499248D02*
X2321115Y-499665D01*
X2320735Y-499915D01*
X2320291Y-499998D01*
X2319785Y-499831D01*
X2319405Y-499415D01*
X2319151Y-498915D01*
X2319088Y-498331D01*
X2319151Y-497748D01*
X2319405Y-497248D01*
X2319785Y-496831D01*
X2320291Y-496665D01*
X2320735Y-496748D01*
X2321051Y-496915D01*
X2321368Y-497248D01*
G01X2324378Y-497748D02*
X2326405D01*
X2326215Y-497165D01*
X2325898Y-496831D01*
X2325455Y-496665D01*
X2325011Y-496748D01*
X2324631Y-496998D01*
X2324378Y-497581D01*
X2324251Y-498081D01*
Y-498581D01*
X2324378Y-499081D01*
X2324695Y-499581D01*
X2325075Y-499915D01*
X2325518Y-499998D01*
X2325961Y-499831D01*
X2326405Y-499331D01*
G01X2329541Y-499998D02*
Y-496665D01*
G01Y-497331D02*
X2329858Y-496998D01*
X2330175Y-496748D01*
X2330618Y-496665D01*
X2330935Y-496748D01*
X2331315Y-496998D01*
G01X2333628Y-499998D02*
Y-496665D01*
G01Y-497581D02*
X2333818Y-497165D01*
X2334135Y-496831D01*
X2334578Y-496665D01*
X2335021Y-496831D01*
X2335338Y-497165D01*
X2335528Y-497581D01*
Y-499998D01*
G01Y-497581D02*
X2335718Y-497165D01*
X2336035Y-496831D01*
X2336478Y-496665D01*
X2336921Y-496831D01*
X2337238Y-497165D01*
X2337428Y-497665D01*
Y-499998D01*
G01X2341768D02*
Y-496665D01*
G01Y-497248D02*
X2341515Y-496915D01*
X2341135Y-496748D01*
X2340691Y-496665D01*
X2340248Y-496831D01*
X2339868Y-497165D01*
X2339615Y-497665D01*
X2339488Y-498331D01*
X2339615Y-498998D01*
X2339868Y-499498D01*
X2340248Y-499831D01*
X2340691Y-499998D01*
X2341135Y-499915D01*
X2341515Y-499665D01*
X2341768Y-499331D01*
G01X2344778Y-499415D02*
X2345095Y-499748D01*
X2345538Y-499998D01*
X2345918D01*
X2346298Y-499831D01*
X2346551Y-499581D01*
X2346678Y-499248D01*
X2346615Y-498748D01*
X2346361Y-498498D01*
X2345221Y-497998D01*
X2344968Y-497415D01*
X2345095Y-496998D01*
X2345348Y-496748D01*
X2345728Y-496665D01*
X2346108Y-496748D01*
X2346488Y-496998D01*
G01X2349751Y-499998D02*
Y-494998D01*
G01X2351778Y-496665D02*
X2349751Y-498581D01*
G01X2350575Y-497831D02*
X2351905Y-499998D01*
G01X2238628Y-507598D02*
Y-512598D01*
G01X2237171Y-507598D02*
X2240085D01*
G01X2243728Y-512598D02*
X2243348Y-512515D01*
X2242968Y-512181D01*
X2242715Y-511598D01*
X2242588Y-510931D01*
X2242715Y-510265D01*
X2242968Y-509681D01*
X2243348Y-509348D01*
X2243728Y-509265D01*
X2244108Y-509348D01*
X2244488Y-509681D01*
X2244741Y-510265D01*
X2244805Y-510931D01*
X2244741Y-511598D01*
X2244488Y-512181D01*
X2244108Y-512515D01*
X2243728Y-512598D01*
G01X2247688Y-514265D02*
Y-509265D01*
G01Y-510015D02*
X2248005Y-509598D01*
X2248321Y-509348D01*
X2248828Y-509265D01*
X2249271Y-509348D01*
X2249715Y-509765D01*
X2249905Y-510348D01*
X2249968Y-510931D01*
X2249905Y-511515D01*
X2249715Y-512098D01*
X2249335Y-512431D01*
X2248828Y-512598D01*
X2248385Y-512515D01*
X2247941Y-512265D01*
X2247688Y-511931D01*
G01X2257445Y-512598D02*
X2259028Y-507598D01*
X2260611Y-512598D01*
G01X2260041Y-510848D02*
X2258015D01*
G01X2263051Y-512598D02*
Y-509265D01*
G01Y-510098D02*
X2263305Y-509681D01*
X2263685Y-509348D01*
X2264191Y-509265D01*
X2264635Y-509348D01*
X2265015Y-509681D01*
X2265205Y-510265D01*
Y-512598D01*
G01X2270368Y-507598D02*
Y-512598D01*
G01Y-511848D02*
X2270115Y-512265D01*
X2269735Y-512515D01*
X2269291Y-512598D01*
X2268785Y-512431D01*
X2268405Y-512015D01*
X2268151Y-511515D01*
X2268088Y-510931D01*
X2268151Y-510348D01*
X2268405Y-509848D01*
X2268785Y-509431D01*
X2269291Y-509265D01*
X2269735Y-509348D01*
X2270051Y-509515D01*
X2270368Y-509848D01*
G01X2279935Y-509931D02*
X2280188Y-509681D01*
X2280378Y-509265D01*
X2280505Y-508681D01*
X2280378Y-508181D01*
X2280125Y-507848D01*
X2279681Y-507598D01*
X2277971D01*
Y-512598D01*
X2280061D01*
X2280505Y-512265D01*
X2280758Y-511765D01*
X2280885Y-511181D01*
X2280758Y-510598D01*
X2280378Y-510098D01*
X2279935Y-509931D01*
X2277971D01*
G01X2284528Y-512598D02*
X2284148Y-512515D01*
X2283768Y-512181D01*
X2283515Y-511598D01*
X2283388Y-510931D01*
X2283515Y-510265D01*
X2283768Y-509681D01*
X2284148Y-509348D01*
X2284528Y-509265D01*
X2284908Y-509348D01*
X2285288Y-509681D01*
X2285541Y-510265D01*
X2285605Y-510931D01*
X2285541Y-511598D01*
X2285288Y-512181D01*
X2284908Y-512515D01*
X2284528Y-512598D01*
G01X2289628Y-507598D02*
Y-512598D01*
G01X2288741Y-509265D02*
X2290515D01*
G01X2294728Y-507598D02*
Y-512598D01*
G01X2293841Y-509265D02*
X2295615D01*
G01X2299828Y-512598D02*
X2299448Y-512515D01*
X2299068Y-512181D01*
X2298815Y-511598D01*
X2298688Y-510931D01*
X2298815Y-510265D01*
X2299068Y-509681D01*
X2299448Y-509348D01*
X2299828Y-509265D01*
X2300208Y-509348D01*
X2300588Y-509681D01*
X2300841Y-510265D01*
X2300905Y-510931D01*
X2300841Y-511598D01*
X2300588Y-512181D01*
X2300208Y-512515D01*
X2299828Y-512598D01*
G01X2303028D02*
Y-509265D01*
G01Y-510181D02*
X2303218Y-509765D01*
X2303535Y-509431D01*
X2303978Y-509265D01*
X2304421Y-509431D01*
X2304738Y-509765D01*
X2304928Y-510181D01*
Y-512598D01*
G01Y-510181D02*
X2305118Y-509765D01*
X2305435Y-509431D01*
X2305878Y-509265D01*
X2306321Y-509431D01*
X2306638Y-509765D01*
X2306828Y-510265D01*
Y-512598D01*
G01X2313798Y-511931D02*
X2314305Y-512348D01*
X2314875Y-512598D01*
X2315381D01*
X2315888Y-512348D01*
X2316268Y-511931D01*
X2316458Y-511348D01*
X2316331Y-510765D01*
X2316015Y-510265D01*
X2315445Y-509931D01*
X2314685Y-509765D01*
X2314241Y-509431D01*
X2314051Y-508848D01*
X2314178Y-508265D01*
X2314495Y-507848D01*
X2314938Y-507598D01*
X2315381D01*
X2315825Y-507765D01*
X2316205Y-508181D01*
G01X2320228Y-509265D02*
Y-512598D01*
G01Y-507931D02*
X2320101Y-507848D01*
Y-507681D01*
X2320228Y-507598D01*
X2320355Y-507681D01*
Y-507848D01*
X2320228Y-507931D01*
G01X2326468Y-507598D02*
Y-512598D01*
G01Y-511848D02*
X2326215Y-512265D01*
X2325835Y-512515D01*
X2325391Y-512598D01*
X2324885Y-512431D01*
X2324505Y-512015D01*
X2324251Y-511515D01*
X2324188Y-510931D01*
X2324251Y-510348D01*
X2324505Y-509848D01*
X2324885Y-509431D01*
X2325391Y-509265D01*
X2325835Y-509348D01*
X2326151Y-509515D01*
X2326468Y-509848D01*
G01X2329478Y-510348D02*
X2331505D01*
X2331315Y-509765D01*
X2330998Y-509431D01*
X2330555Y-509265D01*
X2330111Y-509348D01*
X2329731Y-509598D01*
X2329478Y-510181D01*
X2329351Y-510681D01*
Y-511181D01*
X2329478Y-511681D01*
X2329795Y-512181D01*
X2330175Y-512515D01*
X2330618Y-512598D01*
X2331061Y-512431D01*
X2331505Y-511931D01*
G01X2234316Y-425706D02*
Y-430706D01*
G01X2232859Y-425706D02*
X2235773D01*
G01X2239416Y-430706D02*
X2239036Y-430623D01*
X2238656Y-430289D01*
X2238403Y-429706D01*
X2238276Y-429039D01*
X2238403Y-428373D01*
X2238656Y-427789D01*
X2239036Y-427456D01*
X2239416Y-427373D01*
X2239796Y-427456D01*
X2240176Y-427789D01*
X2240429Y-428373D01*
X2240493Y-429039D01*
X2240429Y-429706D01*
X2240176Y-430289D01*
X2239796Y-430623D01*
X2239416Y-430706D01*
G01X2244516D02*
Y-425706D01*
G01X2248666Y-428456D02*
X2250693D01*
X2250503Y-427873D01*
X2250186Y-427539D01*
X2249743Y-427373D01*
X2249299Y-427456D01*
X2248919Y-427706D01*
X2248666Y-428289D01*
X2248539Y-428789D01*
Y-429289D01*
X2248666Y-429789D01*
X2248983Y-430289D01*
X2249363Y-430623D01*
X2249806Y-430706D01*
X2250249Y-430539D01*
X2250693Y-430039D01*
G01X2253829Y-430706D02*
Y-427373D01*
G01Y-428039D02*
X2254146Y-427706D01*
X2254463Y-427456D01*
X2254906Y-427373D01*
X2255223Y-427456D01*
X2255603Y-427706D01*
G01X2260956Y-430706D02*
Y-427373D01*
G01Y-427956D02*
X2260703Y-427623D01*
X2260323Y-427456D01*
X2259879Y-427373D01*
X2259436Y-427539D01*
X2259056Y-427873D01*
X2258803Y-428373D01*
X2258676Y-429039D01*
X2258803Y-429706D01*
X2259056Y-430206D01*
X2259436Y-430539D01*
X2259879Y-430706D01*
X2260323Y-430623D01*
X2260703Y-430373D01*
X2260956Y-430039D01*
G01X2263839Y-430706D02*
Y-427373D01*
G01Y-428206D02*
X2264093Y-427789D01*
X2264473Y-427456D01*
X2264979Y-427373D01*
X2265423Y-427456D01*
X2265803Y-427789D01*
X2265993Y-428373D01*
Y-430706D01*
G01X2271029Y-427789D02*
X2270586Y-427456D01*
X2270206Y-427373D01*
X2269699Y-427539D01*
X2269319Y-427873D01*
X2269066Y-428456D01*
X2269003Y-429039D01*
X2269066Y-429623D01*
X2269319Y-430123D01*
X2269699Y-430539D01*
X2270206Y-430706D01*
X2270649Y-430539D01*
X2271029Y-430206D01*
G01X2274166Y-428456D02*
X2276193D01*
X2276003Y-427873D01*
X2275686Y-427539D01*
X2275243Y-427373D01*
X2274799Y-427456D01*
X2274419Y-427706D01*
X2274166Y-428289D01*
X2274039Y-428789D01*
Y-429289D01*
X2274166Y-429789D01*
X2274483Y-430289D01*
X2274863Y-430623D01*
X2275306Y-430706D01*
X2275749Y-430539D01*
X2276193Y-430039D01*
G01X2284619Y-429039D02*
X2286139D01*
G01X2285316Y-427956D02*
Y-430123D01*
G01X2290416Y-425706D02*
X2289909Y-425873D01*
X2289529Y-426289D01*
X2289276Y-426789D01*
X2289086Y-427456D01*
X2289023Y-428206D01*
X2289086Y-428956D01*
X2289276Y-429623D01*
X2289529Y-430123D01*
X2289909Y-430539D01*
X2290416Y-430706D01*
X2290923Y-430539D01*
X2291303Y-430123D01*
X2291556Y-429623D01*
X2291746Y-428956D01*
X2291809Y-428206D01*
X2291746Y-427456D01*
X2291556Y-426789D01*
X2291303Y-426289D01*
X2290923Y-425873D01*
X2290416Y-425706D01*
G01X2295516Y-430873D02*
X2295389Y-430789D01*
Y-430623D01*
X2295516Y-430539D01*
X2295643Y-430623D01*
Y-430789D01*
X2295516Y-430873D01*
G01X2300616Y-425706D02*
X2300109Y-425873D01*
X2299729Y-426289D01*
X2299476Y-426789D01*
X2299286Y-427456D01*
X2299223Y-428206D01*
X2299286Y-428956D01*
X2299476Y-429623D01*
X2299729Y-430123D01*
X2300109Y-430539D01*
X2300616Y-430706D01*
X2301123Y-430539D01*
X2301503Y-430123D01*
X2301756Y-429623D01*
X2301946Y-428956D01*
X2302009Y-428206D01*
X2301946Y-427456D01*
X2301756Y-426789D01*
X2301503Y-426289D01*
X2301123Y-425873D01*
X2300616Y-425706D01*
G01X2304323Y-429956D02*
X2304703Y-430373D01*
X2305146Y-430623D01*
X2305716Y-430706D01*
X2306286Y-430539D01*
X2306729Y-430206D01*
X2307046Y-429623D01*
X2307109Y-428956D01*
X2306983Y-428289D01*
X2306666Y-427873D01*
X2306223Y-427539D01*
X2305779Y-427456D01*
X2305336Y-427539D01*
X2304766Y-427873D01*
X2304956Y-425706D01*
X2306666D01*
G01X2310816D02*
X2310309Y-425873D01*
X2309929Y-426289D01*
X2309676Y-426789D01*
X2309486Y-427456D01*
X2309423Y-428206D01*
X2309486Y-428956D01*
X2309676Y-429623D01*
X2309929Y-430123D01*
X2310309Y-430539D01*
X2310816Y-430706D01*
X2311323Y-430539D01*
X2311703Y-430123D01*
X2311956Y-429623D01*
X2312146Y-428956D01*
X2312209Y-428206D01*
X2312146Y-427456D01*
X2311956Y-426789D01*
X2311703Y-426289D01*
X2311323Y-425873D01*
X2310816Y-425706D01*
G01X2315916Y-430706D02*
X2316359Y-430623D01*
X2316866Y-430373D01*
X2317183Y-429956D01*
X2317309Y-429373D01*
X2317183Y-428789D01*
X2316803Y-428289D01*
X2316233Y-428039D01*
X2315599D01*
X2315219Y-427873D01*
X2314903Y-427456D01*
X2314776Y-426873D01*
X2314966Y-426289D01*
X2315409Y-425873D01*
X2315916Y-425706D01*
X2316423Y-425873D01*
X2316866Y-426289D01*
X2317056Y-426873D01*
X2316929Y-427456D01*
X2316613Y-427873D01*
X2316233Y-428039D01*
X2315599D01*
X2315029Y-428289D01*
X2314649Y-428789D01*
X2314523Y-429373D01*
X2314649Y-429956D01*
X2314966Y-430373D01*
X2315473Y-430623D01*
X2315916Y-430706D01*
G01X2319116D02*
Y-427373D01*
G01Y-428289D02*
X2319306Y-427873D01*
X2319623Y-427539D01*
X2320066Y-427373D01*
X2320509Y-427539D01*
X2320826Y-427873D01*
X2321016Y-428289D01*
Y-430706D01*
G01Y-428289D02*
X2321206Y-427873D01*
X2321523Y-427539D01*
X2321966Y-427373D01*
X2322409Y-427539D01*
X2322726Y-427873D01*
X2322916Y-428373D01*
Y-430706D01*
G01X2324216D02*
Y-427373D01*
G01Y-428289D02*
X2324406Y-427873D01*
X2324723Y-427539D01*
X2325166Y-427373D01*
X2325609Y-427539D01*
X2325926Y-427873D01*
X2326116Y-428289D01*
Y-430706D01*
G01Y-428289D02*
X2326306Y-427873D01*
X2326623Y-427539D01*
X2327066Y-427373D01*
X2327509Y-427539D01*
X2327826Y-427873D01*
X2328016Y-428373D01*
Y-430706D01*
G01X2330076Y-430873D02*
X2332356Y-425706D01*
G01X2335493Y-429039D02*
X2337139D01*
G01X2341416Y-425706D02*
X2340909Y-425873D01*
X2340529Y-426289D01*
X2340276Y-426789D01*
X2340086Y-427456D01*
X2340023Y-428206D01*
X2340086Y-428956D01*
X2340276Y-429623D01*
X2340529Y-430123D01*
X2340909Y-430539D01*
X2341416Y-430706D01*
X2341923Y-430539D01*
X2342303Y-430123D01*
X2342556Y-429623D01*
X2342746Y-428956D01*
X2342809Y-428206D01*
X2342746Y-427456D01*
X2342556Y-426789D01*
X2342303Y-426289D01*
X2341923Y-425873D01*
X2341416Y-425706D01*
G01X2346516Y-430873D02*
X2346389Y-430789D01*
Y-430623D01*
X2346516Y-430539D01*
X2346643Y-430623D01*
Y-430789D01*
X2346516Y-430873D01*
G01X2351616Y-425706D02*
X2351109Y-425873D01*
X2350729Y-426289D01*
X2350476Y-426789D01*
X2350286Y-427456D01*
X2350223Y-428206D01*
X2350286Y-428956D01*
X2350476Y-429623D01*
X2350729Y-430123D01*
X2351109Y-430539D01*
X2351616Y-430706D01*
X2352123Y-430539D01*
X2352503Y-430123D01*
X2352756Y-429623D01*
X2352946Y-428956D01*
X2353009Y-428206D01*
X2352946Y-427456D01*
X2352756Y-426789D01*
X2352503Y-426289D01*
X2352123Y-425873D01*
X2351616Y-425706D01*
G01X2356716D02*
X2356209Y-425873D01*
X2355829Y-426289D01*
X2355576Y-426789D01*
X2355386Y-427456D01*
X2355323Y-428206D01*
X2355386Y-428956D01*
X2355576Y-429623D01*
X2355829Y-430123D01*
X2356209Y-430539D01*
X2356716Y-430706D01*
X2357223Y-430539D01*
X2357603Y-430123D01*
X2357856Y-429623D01*
X2358046Y-428956D01*
X2358109Y-428206D01*
X2358046Y-427456D01*
X2357856Y-426789D01*
X2357603Y-426289D01*
X2357223Y-425873D01*
X2356716Y-425706D01*
G01X2361816D02*
X2361309Y-425873D01*
X2360929Y-426289D01*
X2360676Y-426789D01*
X2360486Y-427456D01*
X2360423Y-428206D01*
X2360486Y-428956D01*
X2360676Y-429623D01*
X2360929Y-430123D01*
X2361309Y-430539D01*
X2361816Y-430706D01*
X2362323Y-430539D01*
X2362703Y-430123D01*
X2362956Y-429623D01*
X2363146Y-428956D01*
X2363209Y-428206D01*
X2363146Y-427456D01*
X2362956Y-426789D01*
X2362703Y-426289D01*
X2362323Y-425873D01*
X2361816Y-425706D01*
G01X2366916D02*
X2366409Y-425873D01*
X2366029Y-426289D01*
X2365776Y-426789D01*
X2365586Y-427456D01*
X2365523Y-428206D01*
X2365586Y-428956D01*
X2365776Y-429623D01*
X2366029Y-430123D01*
X2366409Y-430539D01*
X2366916Y-430706D01*
X2367423Y-430539D01*
X2367803Y-430123D01*
X2368056Y-429623D01*
X2368246Y-428956D01*
X2368309Y-428206D01*
X2368246Y-427456D01*
X2368056Y-426789D01*
X2367803Y-426289D01*
X2367423Y-425873D01*
X2366916Y-425706D01*
G01X2370116Y-430706D02*
Y-427373D01*
G01Y-428289D02*
X2370306Y-427873D01*
X2370623Y-427539D01*
X2371066Y-427373D01*
X2371509Y-427539D01*
X2371826Y-427873D01*
X2372016Y-428289D01*
Y-430706D01*
G01Y-428289D02*
X2372206Y-427873D01*
X2372523Y-427539D01*
X2372966Y-427373D01*
X2373409Y-427539D01*
X2373726Y-427873D01*
X2373916Y-428373D01*
Y-430706D01*
G01X2375216D02*
Y-427373D01*
G01Y-428289D02*
X2375406Y-427873D01*
X2375723Y-427539D01*
X2376166Y-427373D01*
X2376609Y-427539D01*
X2376926Y-427873D01*
X2377116Y-428289D01*
Y-430706D01*
G01Y-428289D02*
X2377306Y-427873D01*
X2377623Y-427539D01*
X2378066Y-427373D01*
X2378509Y-427539D01*
X2378826Y-427873D01*
X2379016Y-428373D01*
Y-430706D01*
G01X2162916Y-413106D02*
Y-418106D01*
G01X2161459Y-413106D02*
X2164373D01*
G01X2168016Y-418106D02*
X2167636Y-418023D01*
X2167256Y-417689D01*
X2167003Y-417106D01*
X2166876Y-416439D01*
X2167003Y-415773D01*
X2167256Y-415189D01*
X2167636Y-414856D01*
X2168016Y-414773D01*
X2168396Y-414856D01*
X2168776Y-415189D01*
X2169029Y-415773D01*
X2169093Y-416439D01*
X2169029Y-417106D01*
X2168776Y-417689D01*
X2168396Y-418023D01*
X2168016Y-418106D01*
G01X2173116D02*
X2172736Y-418023D01*
X2172356Y-417689D01*
X2172103Y-417106D01*
X2171976Y-416439D01*
X2172103Y-415773D01*
X2172356Y-415189D01*
X2172736Y-414856D01*
X2173116Y-414773D01*
X2173496Y-414856D01*
X2173876Y-415189D01*
X2174129Y-415773D01*
X2174193Y-416439D01*
X2174129Y-417106D01*
X2173876Y-417689D01*
X2173496Y-418023D01*
X2173116Y-418106D01*
G01X2178216D02*
Y-413106D01*
G01X2183316Y-414773D02*
Y-418106D01*
G01Y-413439D02*
X2183189Y-413356D01*
Y-413189D01*
X2183316Y-413106D01*
X2183443Y-413189D01*
Y-413356D01*
X2183316Y-413439D01*
G01X2187339Y-418106D02*
Y-414773D01*
G01Y-415606D02*
X2187593Y-415189D01*
X2187973Y-414856D01*
X2188479Y-414773D01*
X2188923Y-414856D01*
X2189303Y-415189D01*
X2189493Y-415773D01*
Y-418106D01*
G01X2192629Y-419356D02*
X2193073Y-419689D01*
X2193579Y-419773D01*
X2194023Y-419689D01*
X2194403Y-419273D01*
X2194656Y-418689D01*
Y-414773D01*
G01Y-415439D02*
X2194403Y-415106D01*
X2194023Y-414856D01*
X2193579Y-414773D01*
X2193073Y-414939D01*
X2192756Y-415273D01*
X2192503Y-415856D01*
X2192376Y-416439D01*
X2192439Y-416939D01*
X2192693Y-417523D01*
X2193073Y-417939D01*
X2193579Y-418106D01*
X2193959Y-418023D01*
X2194403Y-417689D01*
X2194656Y-417356D01*
G01X2202386Y-418106D02*
Y-413106D01*
G01X2205046D02*
Y-418106D01*
G01Y-415606D02*
X2202386D01*
G01X2208816Y-418106D02*
X2208436Y-418023D01*
X2208056Y-417689D01*
X2207803Y-417106D01*
X2207676Y-416439D01*
X2207803Y-415773D01*
X2208056Y-415189D01*
X2208436Y-414856D01*
X2208816Y-414773D01*
X2209196Y-414856D01*
X2209576Y-415189D01*
X2209829Y-415773D01*
X2209893Y-416439D01*
X2209829Y-417106D01*
X2209576Y-417689D01*
X2209196Y-418023D01*
X2208816Y-418106D01*
G01X2213916D02*
Y-413106D01*
G01X2218066Y-415856D02*
X2220093D01*
X2219903Y-415273D01*
X2219586Y-414939D01*
X2219143Y-414773D01*
X2218699Y-414856D01*
X2218319Y-415106D01*
X2218066Y-415689D01*
X2217939Y-416189D01*
Y-416689D01*
X2218066Y-417189D01*
X2218383Y-417689D01*
X2218763Y-418023D01*
X2219206Y-418106D01*
X2219649Y-417939D01*
X2220093Y-417439D01*
G01X2224116Y-418273D02*
X2223989Y-418189D01*
Y-418023D01*
X2224116Y-417939D01*
X2224243Y-418023D01*
Y-418189D01*
X2224116Y-418273D01*
G01Y-416023D02*
X2223989Y-415939D01*
Y-415773D01*
X2224116Y-415689D01*
X2224243Y-415773D01*
Y-415939D01*
X2224116Y-416023D01*
G01X2232923Y-418106D02*
Y-413106D01*
X2234189D01*
X2234696Y-413356D01*
X2235076Y-413689D01*
X2235393Y-414189D01*
X2235646Y-414773D01*
X2235709Y-415606D01*
X2235646Y-416439D01*
X2235393Y-417023D01*
X2235076Y-417523D01*
X2234696Y-417856D01*
X2234189Y-418106D01*
X2232923D01*
G01X2239416Y-414773D02*
Y-418106D01*
G01Y-413439D02*
X2239289Y-413356D01*
Y-413189D01*
X2239416Y-413106D01*
X2239543Y-413189D01*
Y-413356D01*
X2239416Y-413439D01*
G01X2245656Y-418106D02*
Y-414773D01*
G01Y-415356D02*
X2245403Y-415023D01*
X2245023Y-414856D01*
X2244579Y-414773D01*
X2244136Y-414939D01*
X2243756Y-415273D01*
X2243503Y-415773D01*
X2243376Y-416439D01*
X2243503Y-417106D01*
X2243756Y-417606D01*
X2244136Y-417939D01*
X2244579Y-418106D01*
X2245023Y-418023D01*
X2245403Y-417773D01*
X2245656Y-417439D01*
G01X2247716Y-418106D02*
Y-414773D01*
G01Y-415689D02*
X2247906Y-415273D01*
X2248223Y-414939D01*
X2248666Y-414773D01*
X2249109Y-414939D01*
X2249426Y-415273D01*
X2249616Y-415689D01*
Y-418106D01*
G01Y-415689D02*
X2249806Y-415273D01*
X2250123Y-414939D01*
X2250566Y-414773D01*
X2251009Y-414939D01*
X2251326Y-415273D01*
X2251516Y-415773D01*
Y-418106D01*
G01X2253766Y-415856D02*
X2255793D01*
X2255603Y-415273D01*
X2255286Y-414939D01*
X2254843Y-414773D01*
X2254399Y-414856D01*
X2254019Y-415106D01*
X2253766Y-415689D01*
X2253639Y-416189D01*
Y-416689D01*
X2253766Y-417189D01*
X2254083Y-417689D01*
X2254463Y-418023D01*
X2254906Y-418106D01*
X2255349Y-417939D01*
X2255793Y-417439D01*
G01X2259816Y-413106D02*
Y-418106D01*
G01X2258929Y-414773D02*
X2260703D01*
G01X2263966Y-415856D02*
X2265993D01*
X2265803Y-415273D01*
X2265486Y-414939D01*
X2265043Y-414773D01*
X2264599Y-414856D01*
X2264219Y-415106D01*
X2263966Y-415689D01*
X2263839Y-416189D01*
Y-416689D01*
X2263966Y-417189D01*
X2264283Y-417689D01*
X2264663Y-418023D01*
X2265106Y-418106D01*
X2265549Y-417939D01*
X2265993Y-417439D01*
G01X2269129Y-418106D02*
Y-414773D01*
G01Y-415439D02*
X2269446Y-415106D01*
X2269763Y-414856D01*
X2270206Y-414773D01*
X2270523Y-414856D01*
X2270903Y-415106D01*
G01X2278823Y-417106D02*
X2279203Y-417689D01*
X2279709Y-418023D01*
X2280279Y-418106D01*
X2280786Y-418023D01*
X2281293Y-417606D01*
X2281609Y-417106D01*
X2281673Y-416606D01*
X2281546Y-416023D01*
X2281103Y-415606D01*
X2280659Y-415439D01*
X2280089D01*
G01X2280659D02*
X2281039Y-415189D01*
X2281356Y-414773D01*
X2281483Y-414273D01*
X2281356Y-413773D01*
X2281039Y-413356D01*
X2280469Y-413106D01*
X2279899Y-413189D01*
X2279329Y-413523D01*
G01X2285316Y-418273D02*
X2285189Y-418189D01*
Y-418023D01*
X2285316Y-417939D01*
X2285443Y-418023D01*
Y-418189D01*
X2285316Y-418273D01*
G01X2290416Y-418106D02*
Y-413106D01*
X2289656Y-414106D01*
G01Y-418106D02*
X2291176D01*
G01X2295389D02*
X2295516Y-417023D01*
X2295706Y-416106D01*
X2295959Y-415273D01*
X2296276Y-414356D01*
X2296783Y-413106D01*
X2294249D01*
G01X2299223Y-417356D02*
X2299603Y-417773D01*
X2300046Y-418023D01*
X2300616Y-418106D01*
X2301186Y-417939D01*
X2301629Y-417606D01*
X2301946Y-417023D01*
X2302009Y-416356D01*
X2301883Y-415689D01*
X2301566Y-415273D01*
X2301123Y-414939D01*
X2300679Y-414856D01*
X2300236Y-414939D01*
X2299666Y-415273D01*
X2299856Y-413106D01*
X2301566D01*
G01X2303816Y-418106D02*
Y-414773D01*
G01Y-415689D02*
X2304006Y-415273D01*
X2304323Y-414939D01*
X2304766Y-414773D01*
X2305209Y-414939D01*
X2305526Y-415273D01*
X2305716Y-415689D01*
Y-418106D01*
G01Y-415689D02*
X2305906Y-415273D01*
X2306223Y-414939D01*
X2306666Y-414773D01*
X2307109Y-414939D01*
X2307426Y-415273D01*
X2307616Y-415773D01*
Y-418106D01*
G01X2308916D02*
Y-414773D01*
G01Y-415689D02*
X2309106Y-415273D01*
X2309423Y-414939D01*
X2309866Y-414773D01*
X2310309Y-414939D01*
X2310626Y-415273D01*
X2310816Y-415689D01*
Y-418106D01*
G01Y-415689D02*
X2311006Y-415273D01*
X2311323Y-414939D01*
X2311766Y-414773D01*
X2312209Y-414939D01*
X2312526Y-415273D01*
X2312716Y-415773D01*
Y-418106D01*
G01X2319559D02*
Y-413106D01*
X2322473Y-418106D01*
Y-413106D01*
G01X2324849Y-418106D02*
Y-413106D01*
X2326369D01*
X2326876Y-413356D01*
X2327256Y-413939D01*
X2327383Y-414606D01*
X2327256Y-415273D01*
X2326939Y-415773D01*
X2326369Y-416023D01*
X2324849D01*
G01X2331216Y-413106D02*
Y-418106D01*
G01X2329759Y-413106D02*
X2332673D01*
G01X2334986Y-418106D02*
Y-413106D01*
G01X2337646D02*
Y-418106D01*
G01Y-415606D02*
X2334986D01*
G01X2181672Y-628758D02*
X2181172Y-628378D01*
X2180922Y-627935D01*
X2180839Y-627428D01*
X2181006Y-626795D01*
X2181422Y-626352D01*
X2181922Y-626225D01*
X2182422Y-626288D01*
X2182839Y-626542D01*
X2183672Y-627808D01*
X2184256Y-628378D01*
X2185089Y-628758D01*
X2185839Y-628885D01*
Y-626225D01*
G01X2187354Y-617713D02*
X2188339Y-623618D01*
X2189323Y-617713D01*
X2187354D01*
G01X2188339Y-627555D02*
Y-623618D01*
G01X2189323Y-637398D02*
X2188339Y-631492D01*
X2187354Y-637398D01*
X2189323D01*
G01X2188339Y-627555D02*
Y-631492D01*
G01X2202906D02*
X2187945D01*
G01X2202906Y-623618D02*
X2187945D01*
G01X2190169Y-550878D02*
X2203632Y-572419D01*
G01X2194134Y-555364D02*
X2190169Y-550878D01*
X2192465Y-556407D01*
X2194134Y-555364D01*
G01X2222379Y-645709D02*
X2222759Y-646292D01*
X2223265Y-646626D01*
X2223835Y-646709D01*
X2224342Y-646626D01*
X2224849Y-646209D01*
X2225165Y-645709D01*
X2225229Y-645209D01*
X2225102Y-644626D01*
X2224659Y-644209D01*
X2224215Y-644042D01*
X2223645D01*
G01X2224215D02*
X2224595Y-643792D01*
X2224912Y-643376D01*
X2225039Y-642876D01*
X2224912Y-642376D01*
X2224595Y-641959D01*
X2224025Y-641709D01*
X2223455Y-641792D01*
X2222885Y-642126D01*
G01X2211567Y-650193D02*
X2217472Y-649209D01*
X2211567Y-648224D01*
Y-650193D01*
G01X2223772Y-649209D02*
X2217472D01*
G01Y-629917D02*
Y-649602D01*
G01X2202758Y-566303D02*
X2206998Y-563653D01*
X2205747Y-563539D01*
G01X2202355Y-565659D02*
X2203161Y-566948D01*
G01X2195718Y-548323D02*
X2226047Y-541324D01*
G01X2201251Y-546036D02*
X2195718Y-548323D01*
X2201694Y-547954D01*
X2201251Y-546036D01*
G01X2206362Y-560277D02*
X2197352Y-560012D01*
G01X2204357Y-560144D02*
G03I-2500J0D01*
G01X2218397Y-539498D02*
X2218898Y-539981D01*
X2219467Y-540192D01*
X2220041Y-540145D01*
X2220516Y-539949D01*
X2220916Y-539430D01*
X2221112Y-538871D01*
X2221061Y-538370D01*
X2220807Y-537830D01*
X2220281Y-537524D01*
X2219812Y-537461D01*
X2219256Y-537589D01*
G01X2219812Y-537461D02*
X2220126Y-537132D01*
X2220341Y-536655D01*
X2220352Y-536139D01*
X2220116Y-535680D01*
X2219714Y-535345D01*
X2219102Y-535230D01*
X2218565Y-535439D01*
X2218085Y-535892D01*
G01X2215456Y-534789D02*
X2212271Y-543220D01*
G01X2216364Y-539005D02*
G03I-2501J0D01*
G01X2212016Y-443286D02*
X2212513Y-443774D01*
X2213079Y-443989D01*
X2213654Y-443948D01*
X2214131Y-443757D01*
X2214535Y-443240D01*
X2214736Y-442684D01*
X2214690Y-442182D01*
X2214440Y-441640D01*
X2213917Y-441329D01*
X2213448Y-441262D01*
X2212892Y-441385D01*
G01X2213448Y-441262D02*
X2213765Y-440936D01*
X2213985Y-440460D01*
X2214000Y-439945D01*
X2213768Y-439484D01*
X2213369Y-439146D01*
X2212759Y-439025D01*
X2212220Y-439229D01*
X2211736Y-439678D01*
G01X2218607Y-443022D02*
X2218465Y-442968D01*
X2218429Y-442805D01*
X2218535Y-442697D01*
X2218677Y-442751D01*
X2218713Y-442913D01*
X2218607Y-443022D01*
G01X2223550Y-441757D02*
X2222469Y-436876D01*
X2221943Y-438016D01*
G01X2222808Y-441922D02*
X2224292Y-441593D01*
G01X2228405Y-440683D02*
X2228295Y-439598D01*
X2228282Y-438662D01*
X2228349Y-437793D01*
X2228461Y-436830D01*
X2228685Y-435500D01*
X2226212Y-436047D01*
G01X2231986Y-439122D02*
X2232447Y-439447D01*
X2232933Y-439595D01*
X2233508Y-439553D01*
X2234029Y-439267D01*
X2234389Y-438846D01*
X2234572Y-438208D01*
X2234490Y-437544D01*
X2234222Y-436920D01*
X2233823Y-436582D01*
X2233318Y-436352D01*
X2232867Y-436367D01*
X2232453Y-436544D01*
X2231968Y-436992D01*
X2231685Y-434836D01*
X2233355Y-434466D01*
G01X2195464Y-450536D02*
X2239567Y-440771D01*
G01X2201018Y-448298D02*
X2195464Y-450536D01*
X2201443Y-450220D01*
X2201018Y-448298D01*
G01X2209117Y-438551D02*
X2205856Y-446954D01*
G01X2209986Y-442753D02*
G03I-2500J0D01*
G01X2235189Y-648224D02*
X2229283Y-649209D01*
X2235189Y-650193D01*
Y-648224D01*
G01X2223772Y-649209D02*
X2229283D01*
G01Y-629917D02*
Y-649602D01*
G01X2337790Y-693697D02*
Y-688697D01*
X2339310D01*
X2339817Y-688947D01*
X2340197Y-689530D01*
X2340324Y-690197D01*
X2340197Y-690864D01*
X2339880Y-691364D01*
X2339310Y-691614D01*
X2337790D01*
G01X2345297Y-693697D02*
Y-690364D01*
G01Y-690947D02*
X2345044Y-690614D01*
X2344664Y-690447D01*
X2344220Y-690364D01*
X2343777Y-690530D01*
X2343397Y-690864D01*
X2343144Y-691364D01*
X2343017Y-692030D01*
X2343144Y-692697D01*
X2343397Y-693197D01*
X2343777Y-693530D01*
X2344220Y-693697D01*
X2344664Y-693614D01*
X2345044Y-693364D01*
X2345297Y-693030D01*
G01X2348180Y-693697D02*
Y-690364D01*
G01Y-691197D02*
X2348434Y-690780D01*
X2348814Y-690447D01*
X2349320Y-690364D01*
X2349764Y-690447D01*
X2350144Y-690780D01*
X2350334Y-691364D01*
Y-693697D01*
G01X2353407Y-691447D02*
X2355434D01*
X2355244Y-690864D01*
X2354927Y-690530D01*
X2354484Y-690364D01*
X2354040Y-690447D01*
X2353660Y-690697D01*
X2353407Y-691280D01*
X2353280Y-691780D01*
Y-692280D01*
X2353407Y-692780D01*
X2353724Y-693280D01*
X2354104Y-693614D01*
X2354547Y-693697D01*
X2354990Y-693530D01*
X2355434Y-693030D01*
G01X2359457Y-693697D02*
Y-688697D01*
G01X2368390Y-693697D02*
Y-688697D01*
X2369974D01*
X2370480Y-688947D01*
X2370797Y-689280D01*
X2370924Y-689947D01*
X2370797Y-690614D01*
X2370417Y-691030D01*
X2369974Y-691280D01*
X2368390D01*
G01X2369974D02*
X2370924Y-693697D01*
G01X2373807Y-691447D02*
X2375834D01*
X2375644Y-690864D01*
X2375327Y-690530D01*
X2374884Y-690364D01*
X2374440Y-690447D01*
X2374060Y-690697D01*
X2373807Y-691280D01*
X2373680Y-691780D01*
Y-692280D01*
X2373807Y-692780D01*
X2374124Y-693280D01*
X2374504Y-693614D01*
X2374947Y-693697D01*
X2375390Y-693530D01*
X2375834Y-693030D01*
G01X2378717Y-690364D02*
X2379857Y-693697D01*
X2380997Y-690364D01*
G01X2390564Y-691030D02*
X2390817Y-690780D01*
X2391007Y-690364D01*
X2391134Y-689780D01*
X2391007Y-689280D01*
X2390754Y-688947D01*
X2390310Y-688697D01*
X2388600D01*
Y-693697D01*
X2390690D01*
X2391134Y-693364D01*
X2391387Y-692864D01*
X2391514Y-692280D01*
X2391387Y-691697D01*
X2391007Y-691197D01*
X2390564Y-691030D01*
X2388600D01*
G01X-457143Y-1211429D02*
Y2242857D01*
X4308572D01*
Y-1211429D01*
X-457143D01*
G01X25935Y-774040D02*
G03I-6250J0D01*
G01X25590Y738607D02*
G03I-5905J0D01*
G01X25935Y766166D02*
G03I-6250J0D01*
G01X71650Y-1024800D02*
X69130Y-1024383D01*
X66925Y-1022717D01*
X65035Y-1020217D01*
X63775Y-1017300D01*
X63145Y-1013967D01*
Y-1010633D01*
X63775Y-1007300D01*
X65035Y-1004383D01*
X66925Y-1001884D01*
X69130Y-1000217D01*
X71650Y-999800D01*
X74170Y-1000217D01*
X76375Y-1001884D01*
X78265Y-1004383D01*
X79525Y-1007300D01*
X80155Y-1010633D01*
Y-1013967D01*
X79525Y-1017300D01*
X78265Y-1020217D01*
X76375Y-1022717D01*
X74170Y-1024383D01*
X71650Y-1024800D01*
G01X74170Y-1018133D02*
X77950Y-1024800D01*
G01X91495Y-1008134D02*
Y-1019800D01*
X92755Y-1022717D01*
X94645Y-1024383D01*
X96850Y-1024800D01*
X99055Y-1024383D01*
X100945Y-1022717D01*
X102205Y-1019800D01*
G01Y-1024800D02*
Y-1008134D01*
G01X127720Y-1024800D02*
Y-1008134D01*
G01Y-1011050D02*
X126460Y-1009384D01*
X124570Y-1008550D01*
X122365Y-1008134D01*
X120160Y-1008967D01*
X118270Y-1010633D01*
X117010Y-1013134D01*
X116380Y-1016467D01*
X117010Y-1019800D01*
X118270Y-1022301D01*
X120160Y-1023967D01*
X122365Y-1024800D01*
X124570Y-1024383D01*
X126460Y-1023134D01*
X127720Y-1021467D01*
G01X141895Y-1024800D02*
Y-1008134D01*
G01Y-1012300D02*
X143155Y-1010217D01*
X145045Y-1008550D01*
X147565Y-1008134D01*
X149770Y-1008550D01*
X151660Y-1010217D01*
X152605Y-1013134D01*
Y-1024800D01*
G01X172450Y-999800D02*
Y-1024800D01*
G01X168040Y-1008134D02*
X176860D01*
G01X203320Y-1024800D02*
Y-1008134D01*
G01Y-1011050D02*
X202060Y-1009384D01*
X200170Y-1008550D01*
X197965Y-1008134D01*
X195760Y-1008967D01*
X193870Y-1010633D01*
X192610Y-1013134D01*
X191980Y-1016467D01*
X192610Y-1019800D01*
X193870Y-1022301D01*
X195760Y-1023967D01*
X197965Y-1024800D01*
X200170Y-1024383D01*
X202060Y-1023134D01*
X203320Y-1021467D01*
G01X49820Y-1042350D02*
X51387D01*
Y-1044240D01*
X50917Y-1044870D01*
X50368Y-1045290D01*
X49585Y-1045500D01*
X48802Y-1045290D01*
X48253Y-1044870D01*
X47783Y-1044240D01*
X47470Y-1043505D01*
X47313Y-1042665D01*
Y-1041930D01*
X47470Y-1041300D01*
X47783Y-1040565D01*
X48253Y-1039935D01*
X48723Y-1039515D01*
X49350Y-1039200D01*
X49898D01*
X50525Y-1039410D01*
X50995Y-1039830D01*
G01X53927Y-1039200D02*
Y-1043715D01*
X54240Y-1044660D01*
X54867Y-1045290D01*
X55650Y-1045500D01*
X56433Y-1045290D01*
X57060Y-1044660D01*
X57373Y-1043715D01*
Y-1039200D01*
G01X61010D02*
X62890D01*
G01X61950D02*
Y-1045500D01*
G01X61010D02*
X62890D01*
G01X66605Y-1044660D02*
X67232Y-1045185D01*
X67937Y-1045500D01*
X68563D01*
X69190Y-1045185D01*
X69660Y-1044660D01*
X69895Y-1043925D01*
X69738Y-1043190D01*
X69347Y-1042560D01*
X68642Y-1042140D01*
X67702Y-1041930D01*
X67153Y-1041510D01*
X66918Y-1040775D01*
X67075Y-1040040D01*
X67467Y-1039515D01*
X68015Y-1039200D01*
X68563D01*
X69112Y-1039410D01*
X69582Y-1039935D01*
G01X72905Y-1045500D02*
Y-1039200D01*
G01X76195D02*
Y-1045500D01*
G01Y-1042350D02*
X72905D01*
G01X78892Y-1045500D02*
X80850Y-1039200D01*
X82808Y-1045500D01*
G01X82103Y-1043295D02*
X79597D01*
G01X85348Y-1045500D02*
Y-1039200D01*
X88952Y-1045500D01*
Y-1039200D01*
G01X98027Y-1045500D02*
Y-1039200D01*
X99593D01*
X100220Y-1039515D01*
X100690Y-1039935D01*
X101082Y-1040565D01*
X101395Y-1041300D01*
X101473Y-1042350D01*
X101395Y-1043400D01*
X101082Y-1044135D01*
X100690Y-1044765D01*
X100220Y-1045185D01*
X99593Y-1045500D01*
X98027D01*
G01X105110Y-1039200D02*
X106990D01*
G01X106050D02*
Y-1045500D01*
G01X105110D02*
X106990D01*
G01X110705Y-1044660D02*
X111332Y-1045185D01*
X112037Y-1045500D01*
X112663D01*
X113290Y-1045185D01*
X113760Y-1044660D01*
X113995Y-1043925D01*
X113838Y-1043190D01*
X113447Y-1042560D01*
X112742Y-1042140D01*
X111802Y-1041930D01*
X111253Y-1041510D01*
X111018Y-1040775D01*
X111175Y-1040040D01*
X111567Y-1039515D01*
X112115Y-1039200D01*
X112663D01*
X113212Y-1039410D01*
X113682Y-1039935D01*
G01X118650Y-1039200D02*
Y-1045500D01*
G01X116848Y-1039200D02*
X120452D01*
G01X124950Y-1045710D02*
X124793Y-1045605D01*
Y-1045395D01*
X124950Y-1045290D01*
X125107Y-1045395D01*
Y-1045605D01*
X124950Y-1045710D01*
G01X131093Y-1046655D02*
X131407Y-1045290D01*
G01X137550Y-1039200D02*
Y-1045500D01*
G01X135748Y-1039200D02*
X139352D01*
G01X141892Y-1045500D02*
X143850Y-1039200D01*
X145808Y-1045500D01*
G01X145103Y-1043295D02*
X142597D01*
G01X150150Y-1045500D02*
X149523Y-1045395D01*
X148975Y-1044975D01*
X148505Y-1044345D01*
X148192Y-1043610D01*
X148035Y-1042770D01*
Y-1041930D01*
X148192Y-1041090D01*
X148505Y-1040355D01*
X148975Y-1039725D01*
X149523Y-1039305D01*
X150150Y-1039200D01*
X150777Y-1039305D01*
X151325Y-1039725D01*
X151795Y-1040355D01*
X152108Y-1041090D01*
X152265Y-1041930D01*
Y-1042770D01*
X152108Y-1043610D01*
X151795Y-1044345D01*
X151325Y-1044975D01*
X150777Y-1045395D01*
X150150Y-1045500D01*
G01X156450D02*
Y-1042665D01*
X154883Y-1039200D01*
G01X158017D02*
X156450Y-1042665D01*
G01X161027Y-1039200D02*
Y-1043715D01*
X161340Y-1044660D01*
X161967Y-1045290D01*
X162750Y-1045500D01*
X163533Y-1045290D01*
X164160Y-1044660D01*
X164473Y-1043715D01*
Y-1039200D01*
G01X167092Y-1045500D02*
X169050Y-1039200D01*
X171008Y-1045500D01*
G01X170303Y-1043295D02*
X167797D01*
G01X173548Y-1045500D02*
Y-1039200D01*
X177152Y-1045500D01*
Y-1039200D01*
G01X51073Y-1049725D02*
X50603Y-1049410D01*
X50055Y-1049200D01*
X49428D01*
X48723Y-1049515D01*
X48175Y-1050040D01*
X47783Y-1050670D01*
X47470Y-1051720D01*
X47392Y-1052665D01*
X47548Y-1053610D01*
X47783Y-1054240D01*
X48253Y-1054870D01*
X48802Y-1055290D01*
X49350Y-1055500D01*
X49898D01*
X50447Y-1055290D01*
X50917Y-1054975D01*
X51308Y-1054555D01*
G01X54710Y-1049200D02*
X56590D01*
G01X55650D02*
Y-1055500D01*
G01X54710D02*
X56590D01*
G01X61950Y-1049200D02*
Y-1055500D01*
G01X60148Y-1049200D02*
X63752D01*
G01X68250Y-1055500D02*
Y-1052665D01*
X66683Y-1049200D01*
G01X69817D02*
X68250Y-1052665D01*
G01X79127Y-1054240D02*
X79597Y-1054975D01*
X80223Y-1055395D01*
X80928Y-1055500D01*
X81555Y-1055395D01*
X82182Y-1054870D01*
X82573Y-1054240D01*
X82652Y-1053610D01*
X82495Y-1052875D01*
X81947Y-1052350D01*
X81398Y-1052140D01*
X80693D01*
G01X81398D02*
X81868Y-1051825D01*
X82260Y-1051300D01*
X82417Y-1050670D01*
X82260Y-1050040D01*
X81868Y-1049515D01*
X81163Y-1049200D01*
X80458Y-1049305D01*
X79753Y-1049725D01*
G01X85427Y-1054240D02*
X85897Y-1054975D01*
X86523Y-1055395D01*
X87228Y-1055500D01*
X87855Y-1055395D01*
X88482Y-1054870D01*
X88873Y-1054240D01*
X88952Y-1053610D01*
X88795Y-1052875D01*
X88247Y-1052350D01*
X87698Y-1052140D01*
X86993D01*
G01X87698D02*
X88168Y-1051825D01*
X88560Y-1051300D01*
X88717Y-1050670D01*
X88560Y-1050040D01*
X88168Y-1049515D01*
X87463Y-1049200D01*
X86758Y-1049305D01*
X86053Y-1049725D01*
G01X91727Y-1054240D02*
X92197Y-1054975D01*
X92823Y-1055395D01*
X93528Y-1055500D01*
X94155Y-1055395D01*
X94782Y-1054870D01*
X95173Y-1054240D01*
X95252Y-1053610D01*
X95095Y-1052875D01*
X94547Y-1052350D01*
X93998Y-1052140D01*
X93293D01*
G01X93998D02*
X94468Y-1051825D01*
X94860Y-1051300D01*
X95017Y-1050670D01*
X94860Y-1050040D01*
X94468Y-1049515D01*
X93763Y-1049200D01*
X93058Y-1049305D01*
X92353Y-1049725D01*
G01X99593Y-1055500D02*
X99750Y-1054135D01*
X99985Y-1052980D01*
X100298Y-1051930D01*
X100690Y-1050775D01*
X101317Y-1049200D01*
X98183D01*
G01X105893Y-1055500D02*
X106050Y-1054135D01*
X106285Y-1052980D01*
X106598Y-1051930D01*
X106990Y-1050775D01*
X107617Y-1049200D01*
X104483D01*
G01X112193Y-1056655D02*
X112507Y-1055290D01*
G01X118650Y-1049200D02*
Y-1055500D01*
G01X116848Y-1049200D02*
X120452D01*
G01X122992Y-1055500D02*
X124950Y-1049200D01*
X126908Y-1055500D01*
G01X126203Y-1053295D02*
X123697D01*
G01X130310Y-1049200D02*
X132190D01*
G01X131250D02*
Y-1055500D01*
G01X130310D02*
X132190D01*
G01X135200Y-1049200D02*
X136297Y-1055500D01*
X137550Y-1049200D01*
X138803Y-1055500D01*
X139900Y-1049200D01*
G01X141892Y-1055500D02*
X143850Y-1049200D01*
X145808Y-1055500D01*
G01X145103Y-1053295D02*
X142597D01*
G01X148348Y-1055500D02*
Y-1049200D01*
X151952Y-1055500D01*
Y-1049200D01*
G01X162358Y-1057600D02*
X161575Y-1056550D01*
X161183Y-1055500D01*
Y-1051300D01*
X161575Y-1050250D01*
X162358Y-1049200D01*
G01X173783Y-1055500D02*
Y-1049200D01*
X175742D01*
X176368Y-1049515D01*
X176760Y-1049935D01*
X176917Y-1050775D01*
X176760Y-1051615D01*
X176290Y-1052140D01*
X175742Y-1052455D01*
X173783D01*
G01X175742D02*
X176917Y-1055500D01*
G01X181650Y-1055710D02*
X181493Y-1055605D01*
Y-1055395D01*
X181650Y-1055290D01*
X181807Y-1055395D01*
Y-1055605D01*
X181650Y-1055710D01*
G01X187950Y-1055500D02*
X187323Y-1055395D01*
X186775Y-1054975D01*
X186305Y-1054345D01*
X185992Y-1053610D01*
X185835Y-1052770D01*
Y-1051930D01*
X185992Y-1051090D01*
X186305Y-1050355D01*
X186775Y-1049725D01*
X187323Y-1049305D01*
X187950Y-1049200D01*
X188577Y-1049305D01*
X189125Y-1049725D01*
X189595Y-1050355D01*
X189908Y-1051090D01*
X190065Y-1051930D01*
Y-1052770D01*
X189908Y-1053610D01*
X189595Y-1054345D01*
X189125Y-1054975D01*
X188577Y-1055395D01*
X187950Y-1055500D01*
G01X194250Y-1055710D02*
X194093Y-1055605D01*
Y-1055395D01*
X194250Y-1055290D01*
X194407Y-1055395D01*
Y-1055605D01*
X194250Y-1055710D01*
G01X202273Y-1049725D02*
X201803Y-1049410D01*
X201255Y-1049200D01*
X200628D01*
X199923Y-1049515D01*
X199375Y-1050040D01*
X198983Y-1050670D01*
X198670Y-1051720D01*
X198592Y-1052665D01*
X198748Y-1053610D01*
X198983Y-1054240D01*
X199453Y-1054870D01*
X200002Y-1055290D01*
X200550Y-1055500D01*
X201098D01*
X201647Y-1055290D01*
X202117Y-1054975D01*
X202508Y-1054555D01*
G01X206850Y-1055710D02*
X206693Y-1055605D01*
Y-1055395D01*
X206850Y-1055290D01*
X207007Y-1055395D01*
Y-1055605D01*
X206850Y-1055710D01*
G01X213542Y-1057600D02*
X214325Y-1056550D01*
X214717Y-1055500D01*
Y-1051300D01*
X214325Y-1050250D01*
X213542Y-1049200D01*
G01X47548Y-1035500D02*
Y-1029200D01*
X51152Y-1035500D01*
Y-1029200D01*
G01X55650Y-1035500D02*
X55023Y-1035395D01*
X54475Y-1034975D01*
X54005Y-1034345D01*
X53692Y-1033610D01*
X53535Y-1032770D01*
Y-1031930D01*
X53692Y-1031090D01*
X54005Y-1030355D01*
X54475Y-1029725D01*
X55023Y-1029305D01*
X55650Y-1029200D01*
X56277Y-1029305D01*
X56825Y-1029725D01*
X57295Y-1030355D01*
X57608Y-1031090D01*
X57765Y-1031930D01*
Y-1032770D01*
X57608Y-1033610D01*
X57295Y-1034345D01*
X56825Y-1034975D01*
X56277Y-1035395D01*
X55650Y-1035500D01*
G01X61950Y-1035710D02*
X61793Y-1035605D01*
Y-1035395D01*
X61950Y-1035290D01*
X62107Y-1035395D01*
Y-1035605D01*
X61950Y-1035710D01*
G01X66762Y-1030250D02*
X67232Y-1029620D01*
X67780Y-1029305D01*
X68407Y-1029200D01*
X69190Y-1029410D01*
X69738Y-1029935D01*
X69895Y-1030565D01*
X69817Y-1031195D01*
X69503Y-1031720D01*
X67937Y-1032770D01*
X67232Y-1033505D01*
X66762Y-1034555D01*
X66605Y-1035500D01*
X69895D01*
G01X74550D02*
Y-1029200D01*
X73610Y-1030460D01*
G01Y-1035500D02*
X75490D01*
G01X80850D02*
Y-1029200D01*
X79910Y-1030460D01*
G01Y-1035500D02*
X81790D01*
G01X86993Y-1036655D02*
X87307Y-1035290D01*
G01X91100Y-1029200D02*
X92197Y-1035500D01*
X93450Y-1029200D01*
X94703Y-1035500D01*
X95800Y-1029200D01*
G01X101317Y-1035500D02*
X98183D01*
Y-1029200D01*
X101317D01*
G01X100063Y-1032245D02*
X98183D01*
G01X104248Y-1035500D02*
Y-1029200D01*
X107852Y-1035500D01*
Y-1029200D01*
G01X110705Y-1035500D02*
Y-1029200D01*
G01X113995D02*
Y-1035500D01*
G01Y-1032350D02*
X110705D01*
G01X116927Y-1029200D02*
Y-1033715D01*
X117240Y-1034660D01*
X117867Y-1035290D01*
X118650Y-1035500D01*
X119433Y-1035290D01*
X120060Y-1034660D01*
X120373Y-1033715D01*
Y-1029200D01*
G01X122992Y-1035500D02*
X124950Y-1029200D01*
X126908Y-1035500D01*
G01X126203Y-1033295D02*
X123697D01*
G01X136062Y-1030250D02*
X136532Y-1029620D01*
X137080Y-1029305D01*
X137707Y-1029200D01*
X138490Y-1029410D01*
X139038Y-1029935D01*
X139195Y-1030565D01*
X139117Y-1031195D01*
X138803Y-1031720D01*
X137237Y-1032770D01*
X136532Y-1033505D01*
X136062Y-1034555D01*
X135905Y-1035500D01*
X139195D01*
G01X142048D02*
Y-1029200D01*
X145652Y-1035500D01*
Y-1029200D01*
G01X148427Y-1035500D02*
Y-1029200D01*
X149993D01*
X150620Y-1029515D01*
X151090Y-1029935D01*
X151482Y-1030565D01*
X151795Y-1031300D01*
X151873Y-1032350D01*
X151795Y-1033400D01*
X151482Y-1034135D01*
X151090Y-1034765D01*
X150620Y-1035185D01*
X149993Y-1035500D01*
X148427D01*
G01X161183D02*
Y-1029200D01*
X163142D01*
X163768Y-1029515D01*
X164160Y-1029935D01*
X164317Y-1030775D01*
X164160Y-1031615D01*
X163690Y-1032140D01*
X163142Y-1032455D01*
X161183D01*
G01X163142D02*
X164317Y-1035500D01*
G01X167327D02*
Y-1029200D01*
X168893D01*
X169520Y-1029515D01*
X169990Y-1029935D01*
X170382Y-1030565D01*
X170695Y-1031300D01*
X170773Y-1032350D01*
X170695Y-1033400D01*
X170382Y-1034135D01*
X169990Y-1034765D01*
X169520Y-1035185D01*
X168893Y-1035500D01*
X167327D01*
G01X175350Y-1035710D02*
X175193Y-1035605D01*
Y-1035395D01*
X175350Y-1035290D01*
X175507Y-1035395D01*
Y-1035605D01*
X175350Y-1035710D01*
G01X243000Y-1004500D02*
Y-1012500D01*
X247000D01*
G01X254800D02*
Y-1007167D01*
G01Y-1008100D02*
X254400Y-1007567D01*
X253800Y-1007300D01*
X253100Y-1007167D01*
X252400Y-1007433D01*
X251800Y-1007967D01*
X251400Y-1008767D01*
X251200Y-1009833D01*
X251400Y-1010900D01*
X251800Y-1011700D01*
X252400Y-1012233D01*
X253100Y-1012500D01*
X253800Y-1012367D01*
X254400Y-1011967D01*
X254800Y-1011434D01*
G01X258900Y-1014900D02*
X259500Y-1015167D01*
X260300Y-1014900D01*
X260800Y-1014367D01*
X261200Y-1013700D01*
X261800Y-1011567D01*
X263100Y-1007167D01*
G01X259900D02*
X261800Y-1011567D01*
G01X267500Y-1008900D02*
X270700D01*
X270400Y-1007967D01*
X269900Y-1007433D01*
X269200Y-1007167D01*
X268500Y-1007300D01*
X267900Y-1007700D01*
X267500Y-1008633D01*
X267300Y-1009434D01*
Y-1010233D01*
X267500Y-1011033D01*
X268000Y-1011833D01*
X268600Y-1012367D01*
X269300Y-1012500D01*
X270000Y-1012233D01*
X270700Y-1011434D01*
G01X275600Y-1012500D02*
Y-1007167D01*
G01Y-1008233D02*
X276100Y-1007700D01*
X276600Y-1007300D01*
X277300Y-1007167D01*
X277800Y-1007300D01*
X278400Y-1007700D01*
G01X262100Y-1054500D02*
X265900D01*
X262100Y-1062500D01*
X265900D01*
G01X272000Y-1057167D02*
Y-1062500D01*
G01Y-1055033D02*
X271800Y-1054900D01*
Y-1054633D01*
X272000Y-1054500D01*
X272200Y-1054633D01*
Y-1054900D01*
X272000Y-1055033D01*
G01X278700Y-1059833D02*
X281300D01*
G01X286200Y-1065167D02*
Y-1057167D01*
G01Y-1058367D02*
X286700Y-1057700D01*
X287200Y-1057300D01*
X288000Y-1057167D01*
X288700Y-1057300D01*
X289400Y-1057967D01*
X289700Y-1058900D01*
X289800Y-1059833D01*
X289700Y-1060767D01*
X289400Y-1061700D01*
X288800Y-1062233D01*
X288000Y-1062500D01*
X287300Y-1062367D01*
X286600Y-1061967D01*
X286200Y-1061434D01*
G01X296000Y-1057167D02*
Y-1062500D01*
G01Y-1055033D02*
X295800Y-1054900D01*
Y-1054633D01*
X296000Y-1054500D01*
X296200Y-1054633D01*
Y-1054900D01*
X296000Y-1055033D01*
G01X302300Y-1062500D02*
Y-1057167D01*
G01Y-1058500D02*
X302700Y-1057833D01*
X303300Y-1057300D01*
X304100Y-1057167D01*
X304800Y-1057300D01*
X305400Y-1057833D01*
X305700Y-1058767D01*
Y-1062500D01*
G01X310600Y-1064500D02*
X311300Y-1065033D01*
X312100Y-1065167D01*
X312800Y-1065033D01*
X313400Y-1064367D01*
X313800Y-1063433D01*
Y-1057167D01*
G01Y-1058233D02*
X313400Y-1057700D01*
X312800Y-1057300D01*
X312100Y-1057167D01*
X311300Y-1057433D01*
X310800Y-1057967D01*
X310400Y-1058900D01*
X310200Y-1059833D01*
X310300Y-1060633D01*
X310700Y-1061567D01*
X311300Y-1062233D01*
X312100Y-1062500D01*
X312700Y-1062367D01*
X313400Y-1061833D01*
X313800Y-1061300D01*
G01X262000Y-1037500D02*
Y-1029500D01*
X264400D01*
X265200Y-1029900D01*
X265800Y-1030833D01*
X266000Y-1031900D01*
X265800Y-1032967D01*
X265300Y-1033767D01*
X264400Y-1034167D01*
X262000D01*
G01X269500Y-1037500D02*
X272000Y-1029500D01*
X274500Y-1037500D01*
G01X273600Y-1034700D02*
X270400D01*
G01X277700Y-1037500D02*
Y-1029500D01*
X282300Y-1037500D01*
Y-1029500D01*
G01X290000Y-1037500D02*
X286000D01*
Y-1029500D01*
X290000D01*
G01X288400Y-1033367D02*
X286000D01*
G01X294000Y-1029500D02*
Y-1037500D01*
X298000D01*
G01X369600Y-1055833D02*
X370200Y-1055033D01*
X370900Y-1054633D01*
X371700Y-1054500D01*
X372700Y-1054767D01*
X373400Y-1055433D01*
X373600Y-1056233D01*
X373500Y-1057034D01*
X373100Y-1057700D01*
X371100Y-1059033D01*
X370200Y-1059967D01*
X369600Y-1061300D01*
X369400Y-1062500D01*
X373600D01*
G01X379500Y-1054500D02*
X378700Y-1054767D01*
X378100Y-1055433D01*
X377700Y-1056233D01*
X377400Y-1057300D01*
X377300Y-1058500D01*
X377400Y-1059700D01*
X377700Y-1060767D01*
X378100Y-1061567D01*
X378700Y-1062233D01*
X379500Y-1062500D01*
X380300Y-1062233D01*
X380900Y-1061567D01*
X381300Y-1060767D01*
X381600Y-1059700D01*
X381700Y-1058500D01*
X381600Y-1057300D01*
X381300Y-1056233D01*
X380900Y-1055433D01*
X380300Y-1054767D01*
X379500Y-1054500D01*
G01X385600Y-1055833D02*
X386200Y-1055033D01*
X386900Y-1054633D01*
X387700Y-1054500D01*
X388700Y-1054767D01*
X389400Y-1055433D01*
X389600Y-1056233D01*
X389500Y-1057034D01*
X389100Y-1057700D01*
X387100Y-1059033D01*
X386200Y-1059967D01*
X385600Y-1061300D01*
X385400Y-1062500D01*
X389600D01*
G01X393600Y-1055833D02*
X394200Y-1055033D01*
X394900Y-1054633D01*
X395700Y-1054500D01*
X396700Y-1054767D01*
X397400Y-1055433D01*
X397600Y-1056233D01*
X397500Y-1057034D01*
X397100Y-1057700D01*
X395100Y-1059033D01*
X394200Y-1059967D01*
X393600Y-1061300D01*
X393400Y-1062500D01*
X397600D01*
G01X401700Y-1062767D02*
X405300Y-1054500D01*
G01X411500Y-1062500D02*
Y-1054500D01*
X410300Y-1056100D01*
G01Y-1062500D02*
X412700D01*
G01X417600Y-1055833D02*
X418200Y-1055033D01*
X418900Y-1054633D01*
X419700Y-1054500D01*
X420700Y-1054767D01*
X421400Y-1055433D01*
X421600Y-1056233D01*
X421500Y-1057034D01*
X421100Y-1057700D01*
X419100Y-1059033D01*
X418200Y-1059967D01*
X417600Y-1061300D01*
X417400Y-1062500D01*
X421600D01*
G01X425700Y-1062767D02*
X429300Y-1054500D01*
G01X435500Y-1062500D02*
Y-1054500D01*
X434300Y-1056100D01*
G01Y-1062500D02*
X436700D01*
G01X441300Y-1060900D02*
X441900Y-1061833D01*
X442700Y-1062367D01*
X443600Y-1062500D01*
X444400Y-1062367D01*
X445200Y-1061700D01*
X445700Y-1060900D01*
X445800Y-1060100D01*
X445600Y-1059167D01*
X444900Y-1058500D01*
X444200Y-1058233D01*
X443300D01*
G01X444200D02*
X444800Y-1057833D01*
X445300Y-1057167D01*
X445500Y-1056367D01*
X445300Y-1055567D01*
X444800Y-1054900D01*
X443900Y-1054500D01*
X443000Y-1054633D01*
X442100Y-1055167D01*
G01X369300Y-1040000D02*
Y-1032000D01*
X371300D01*
X372100Y-1032400D01*
X372700Y-1032933D01*
X373200Y-1033733D01*
X373600Y-1034667D01*
X373700Y-1036000D01*
X373600Y-1037333D01*
X373200Y-1038267D01*
X372700Y-1039067D01*
X372100Y-1039600D01*
X371300Y-1040000D01*
X369300D01*
G01X377000D02*
X379500Y-1032000D01*
X382000Y-1040000D01*
G01X381100Y-1037200D02*
X377900D01*
G01X385600Y-1040000D02*
Y-1032000D01*
X389400D01*
G01X388000Y-1035867D02*
X385600D01*
G01X395500Y-1032000D02*
X394700Y-1032267D01*
X394100Y-1032933D01*
X393700Y-1033733D01*
X393400Y-1034800D01*
X393300Y-1036000D01*
X393400Y-1037200D01*
X393700Y-1038267D01*
X394100Y-1039067D01*
X394700Y-1039733D01*
X395500Y-1040000D01*
X396300Y-1039733D01*
X396900Y-1039067D01*
X397300Y-1038267D01*
X397600Y-1037200D01*
X397700Y-1036000D01*
X397600Y-1034800D01*
X397300Y-1033733D01*
X396900Y-1032933D01*
X396300Y-1032267D01*
X395500Y-1032000D01*
G01X403500D02*
Y-1040000D01*
G01X401200Y-1032000D02*
X405800D01*
G01X409500Y-1040000D02*
Y-1032000D01*
X411900D01*
X412700Y-1032400D01*
X413300Y-1033333D01*
X413500Y-1034400D01*
X413300Y-1035467D01*
X412800Y-1036267D01*
X411900Y-1036667D01*
X409500D01*
G01X420300Y-1035733D02*
X420700Y-1035333D01*
X421000Y-1034667D01*
X421200Y-1033733D01*
X421000Y-1032933D01*
X420600Y-1032400D01*
X419900Y-1032000D01*
X417200D01*
Y-1040000D01*
X420500D01*
X421200Y-1039467D01*
X421600Y-1038667D01*
X421800Y-1037733D01*
X421600Y-1036800D01*
X421000Y-1036000D01*
X420300Y-1035733D01*
X417200D01*
G01X427500Y-1040000D02*
Y-1032000D01*
X426300Y-1033600D01*
G01Y-1040000D02*
X428700D01*
G01X433000D02*
X435500Y-1032000D01*
X438000Y-1040000D01*
G01X437100Y-1037200D02*
X433900D01*
G01X441600Y-1040000D02*
Y-1032000D01*
X445400D01*
G01X444000Y-1035867D02*
X441600D01*
G01X451500Y-1032000D02*
X450700Y-1032267D01*
X450100Y-1032933D01*
X449700Y-1033733D01*
X449400Y-1034800D01*
X449300Y-1036000D01*
X449400Y-1037200D01*
X449700Y-1038267D01*
X450100Y-1039067D01*
X450700Y-1039733D01*
X451500Y-1040000D01*
X452300Y-1039733D01*
X452900Y-1039067D01*
X453300Y-1038267D01*
X453600Y-1037200D01*
X453700Y-1036000D01*
X453600Y-1034800D01*
X453300Y-1033733D01*
X452900Y-1032933D01*
X452300Y-1032267D01*
X451500Y-1032000D01*
G01X389600Y-1012500D02*
Y-1004500D01*
X393400D01*
G01X392000Y-1008367D02*
X389600D01*
G01X399500Y-1004500D02*
X398700Y-1004767D01*
X398100Y-1005433D01*
X397700Y-1006233D01*
X397400Y-1007300D01*
X397300Y-1008500D01*
X397400Y-1009700D01*
X397700Y-1010767D01*
X398100Y-1011567D01*
X398700Y-1012233D01*
X399500Y-1012500D01*
X400300Y-1012233D01*
X400900Y-1011567D01*
X401300Y-1010767D01*
X401600Y-1009700D01*
X401700Y-1008500D01*
X401600Y-1007300D01*
X401300Y-1006233D01*
X400900Y-1005433D01*
X400300Y-1004767D01*
X399500Y-1004500D01*
G01X407500D02*
Y-1012500D01*
G01X405200Y-1004500D02*
X409800D01*
G01X412500Y-1015167D02*
X418500D01*
G01X421500Y-1012500D02*
Y-1004500D01*
X423900D01*
X424700Y-1004900D01*
X425300Y-1005833D01*
X425500Y-1006900D01*
X425300Y-1007967D01*
X424800Y-1008767D01*
X423900Y-1009167D01*
X421500D01*
G01X429300Y-1012500D02*
Y-1004500D01*
X431300D01*
X432100Y-1004900D01*
X432700Y-1005433D01*
X433200Y-1006233D01*
X433600Y-1007167D01*
X433700Y-1008500D01*
X433600Y-1009833D01*
X433200Y-1010767D01*
X432700Y-1011567D01*
X432100Y-1012100D01*
X431300Y-1012500D01*
X429300D01*
G01X440300Y-1008233D02*
X440700Y-1007833D01*
X441000Y-1007167D01*
X441200Y-1006233D01*
X441000Y-1005433D01*
X440600Y-1004900D01*
X439900Y-1004500D01*
X437200D01*
Y-1012500D01*
X440500D01*
X441200Y-1011967D01*
X441600Y-1011167D01*
X441800Y-1010233D01*
X441600Y-1009300D01*
X441000Y-1008500D01*
X440300Y-1008233D01*
X437200D01*
G01X444500Y-1015167D02*
X450500D01*
G01X456300Y-1008233D02*
X456700Y-1007833D01*
X457000Y-1007167D01*
X457200Y-1006233D01*
X457000Y-1005433D01*
X456600Y-1004900D01*
X455900Y-1004500D01*
X453200D01*
Y-1012500D01*
X456500D01*
X457200Y-1011967D01*
X457600Y-1011167D01*
X457800Y-1010233D01*
X457600Y-1009300D01*
X457000Y-1008500D01*
X456300Y-1008233D01*
X453200D01*
G01X461300Y-1012500D02*
Y-1004500D01*
X463300D01*
X464100Y-1004900D01*
X464700Y-1005433D01*
X465200Y-1006233D01*
X465600Y-1007167D01*
X465700Y-1008500D01*
X465600Y-1009833D01*
X465200Y-1010767D01*
X464700Y-1011567D01*
X464100Y-1012100D01*
X463300Y-1012500D01*
X461300D01*
G01X468500Y-1015167D02*
X474500D01*
G01X480100Y-1008500D02*
X482100D01*
Y-1010900D01*
X481500Y-1011700D01*
X480800Y-1012233D01*
X479800Y-1012500D01*
X478800Y-1012233D01*
X478100Y-1011700D01*
X477500Y-1010900D01*
X477100Y-1009967D01*
X476900Y-1008900D01*
Y-1007967D01*
X477100Y-1007167D01*
X477500Y-1006233D01*
X478100Y-1005433D01*
X478700Y-1004900D01*
X479500Y-1004500D01*
X480200D01*
X481000Y-1004767D01*
X481600Y-1005300D01*
G01X485500Y-1012500D02*
Y-1004500D01*
X487900D01*
X488700Y-1004900D01*
X489300Y-1005833D01*
X489500Y-1006900D01*
X489300Y-1007967D01*
X488800Y-1008767D01*
X487900Y-1009167D01*
X485500D01*
G01X493300Y-1004500D02*
Y-1010233D01*
X493700Y-1011434D01*
X494500Y-1012233D01*
X495500Y-1012500D01*
X496500Y-1012233D01*
X497300Y-1011434D01*
X497700Y-1010233D01*
Y-1004500D01*
G01X458000Y-1065500D02*
Y-1057500D01*
X456800Y-1059100D01*
G01Y-1065500D02*
X459200D01*
G01X464100Y-1062167D02*
X464800Y-1061233D01*
X465400Y-1060700D01*
X466200Y-1060433D01*
X466900Y-1060700D01*
X467400Y-1061233D01*
X467800Y-1062033D01*
X467900Y-1062967D01*
X467800Y-1063767D01*
X467400Y-1064567D01*
X466800Y-1065233D01*
X466100Y-1065500D01*
X465300Y-1065233D01*
X464600Y-1064434D01*
X464200Y-1063233D01*
X464100Y-1061900D01*
X464300Y-1060167D01*
X464600Y-1059233D01*
X465100Y-1058300D01*
X465800Y-1057633D01*
X466500Y-1057500D01*
X467200Y-1057767D01*
X467700Y-1058433D01*
G01X474000Y-1065767D02*
X473800Y-1065633D01*
Y-1065367D01*
X474000Y-1065233D01*
X474200Y-1065367D01*
Y-1065633D01*
X474000Y-1065767D01*
G01X480100Y-1062167D02*
X480800Y-1061233D01*
X481400Y-1060700D01*
X482200Y-1060433D01*
X482900Y-1060700D01*
X483400Y-1061233D01*
X483800Y-1062033D01*
X483900Y-1062967D01*
X483800Y-1063767D01*
X483400Y-1064567D01*
X482800Y-1065233D01*
X482100Y-1065500D01*
X481300Y-1065233D01*
X480600Y-1064434D01*
X480200Y-1063233D01*
X480100Y-1061900D01*
X480300Y-1060167D01*
X480600Y-1059233D01*
X481100Y-1058300D01*
X481800Y-1057633D01*
X482500Y-1057500D01*
X483200Y-1057767D01*
X483700Y-1058433D01*
G01X503000Y-1065500D02*
Y-1057500D01*
X501800Y-1059100D01*
G01Y-1065500D02*
X504200D01*
G01X510800D02*
X511000Y-1063767D01*
X511300Y-1062300D01*
X511700Y-1060967D01*
X512200Y-1059500D01*
X513000Y-1057500D01*
X509000D01*
G01X519000Y-1065767D02*
X518800Y-1065633D01*
Y-1065367D01*
X519000Y-1065233D01*
X519200Y-1065367D01*
Y-1065633D01*
X519000Y-1065767D01*
G01X525100Y-1058833D02*
X525700Y-1058033D01*
X526400Y-1057633D01*
X527200Y-1057500D01*
X528200Y-1057767D01*
X528900Y-1058433D01*
X529100Y-1059233D01*
X529000Y-1060034D01*
X528600Y-1060700D01*
X526600Y-1062033D01*
X525700Y-1062967D01*
X525100Y-1064300D01*
X524900Y-1065500D01*
X529100D01*
G01X523100Y-1040500D02*
Y-1032500D01*
X526900D01*
G01X525500Y-1036367D02*
X523100D01*
G01X572825Y463701D02*
G03I-6250J0D01*
G01D02*
G03I-6250J0D01*
G01D02*
G03I-6250J0D01*
G01X668682Y457656D02*
X673362D01*
G01X671022D02*
Y442056D01*
G01X668682D02*
X673362D01*
G01X684827Y444136D02*
X686387Y442836D01*
X688142Y442056D01*
X689702D01*
X691262Y442836D01*
X692432Y444136D01*
X693017Y445956D01*
X692627Y447776D01*
X691652Y449336D01*
X689897Y450376D01*
X687557Y450896D01*
X686192Y451936D01*
X685607Y453756D01*
X685997Y455576D01*
X686972Y456876D01*
X688337Y457656D01*
X689702D01*
X691067Y457136D01*
X692237Y455836D01*
G01X706822Y457656D02*
Y442056D01*
G01X702337Y457656D02*
X711307D01*
G01X743792Y449856D02*
X747692D01*
Y445176D01*
X746522Y443616D01*
X745157Y442576D01*
X743207Y442056D01*
X741257Y442576D01*
X739892Y443616D01*
X738722Y445176D01*
X737942Y446996D01*
X737552Y449076D01*
Y450896D01*
X737942Y452456D01*
X738722Y454276D01*
X739892Y455836D01*
X741062Y456876D01*
X742622Y457656D01*
X743987D01*
X745547Y457136D01*
X746717Y456096D01*
G01X764422Y442056D02*
X756622D01*
Y457656D01*
X764422D01*
G01X761302Y450116D02*
X756622D01*
G01X774522Y442056D02*
Y457656D01*
X779397D01*
X780957Y456876D01*
X781932Y455836D01*
X782322Y453756D01*
X781932Y451676D01*
X780762Y450376D01*
X779397Y449596D01*
X774522D01*
G01X779397D02*
X782322Y442056D01*
G01X797882Y450376D02*
X798662Y451156D01*
X799247Y452456D01*
X799637Y454276D01*
X799247Y455836D01*
X798467Y456876D01*
X797102Y457656D01*
X791837D01*
Y442056D01*
X798272D01*
X799637Y443096D01*
X800417Y444656D01*
X800807Y446476D01*
X800417Y448296D01*
X799247Y449856D01*
X797882Y450376D01*
X791837D01*
G01X818122Y442056D02*
X810322D01*
Y457656D01*
X818122D01*
G01X815002Y450116D02*
X810322D01*
G01X828222Y442056D02*
Y457656D01*
X833097D01*
X834657Y456876D01*
X835632Y455836D01*
X836022Y453756D01*
X835632Y451676D01*
X834462Y450376D01*
X833097Y449596D01*
X828222D01*
G01X833097D02*
X836022Y442056D01*
G01X849047Y436856D02*
X847097Y439456D01*
X846122Y442056D01*
Y452456D01*
X847097Y455056D01*
X849047Y457656D01*
G01X867922D02*
Y442056D01*
G01X863437Y457656D02*
X872407D01*
G01X880947D02*
X885822Y442056D01*
X890697Y457656D01*
G01X899627Y442056D02*
X907817Y457656D01*
G01X899627D02*
X907817Y442056D01*
G01X921622D02*
Y457656D01*
X919282Y454536D01*
G01Y442056D02*
X923962D01*
G01X939522Y457656D02*
X937962Y457136D01*
X936792Y455836D01*
X936012Y454276D01*
X935427Y452196D01*
X935232Y449856D01*
X935427Y447516D01*
X936012Y445436D01*
X936792Y443876D01*
X937962Y442576D01*
X939522Y442056D01*
X941082Y442576D01*
X942252Y443876D01*
X943032Y445436D01*
X943617Y447516D01*
X943812Y449856D01*
X943617Y452196D01*
X943032Y454276D01*
X942252Y455836D01*
X941082Y457136D01*
X939522Y457656D01*
G01X953132Y445176D02*
X954302Y443356D01*
X955862Y442316D01*
X957617Y442056D01*
X959177Y442316D01*
X960737Y443616D01*
X961712Y445176D01*
X961907Y446736D01*
X961517Y448556D01*
X960152Y449856D01*
X958787Y450376D01*
X957032D01*
G01X958787D02*
X959957Y451156D01*
X960932Y452456D01*
X961322Y454016D01*
X960932Y455576D01*
X959957Y456876D01*
X958202Y457656D01*
X956447Y457396D01*
X954692Y456356D01*
G01X971617Y448556D02*
X972982Y450376D01*
X974152Y451416D01*
X975712Y451936D01*
X977077Y451416D01*
X978052Y450376D01*
X978832Y448816D01*
X979027Y446996D01*
X978832Y445436D01*
X978052Y443876D01*
X976882Y442576D01*
X975517Y442056D01*
X973957Y442576D01*
X972592Y444136D01*
X971812Y446476D01*
X971617Y449076D01*
X972007Y452456D01*
X972592Y454276D01*
X973567Y456096D01*
X974932Y457396D01*
X976297Y457656D01*
X977662Y457136D01*
X978637Y455836D01*
G01X993222Y442056D02*
X994587Y442316D01*
X996147Y443096D01*
X997122Y444396D01*
X997512Y446216D01*
X997122Y448036D01*
X995952Y449596D01*
X994197Y450376D01*
X992247D01*
X991077Y450896D01*
X990102Y452196D01*
X989712Y454016D01*
X990297Y455836D01*
X991662Y457136D01*
X993222Y457656D01*
X994782Y457136D01*
X996147Y455836D01*
X996732Y454016D01*
X996342Y452196D01*
X995367Y450896D01*
X994197Y450376D01*
X992247D01*
X990492Y449596D01*
X989322Y448036D01*
X988932Y446216D01*
X989322Y444396D01*
X990297Y443096D01*
X991857Y442316D01*
X993222Y442056D01*
G01X1006247D02*
X1011122Y457656D01*
X1015997Y442056D01*
G01X1014242Y447516D02*
X1008002D01*
G01X1029997Y436856D02*
X1031947Y439456D01*
X1032922Y442056D01*
Y452456D01*
X1031947Y455056D01*
X1029997Y457656D01*
G01X905900Y890050D02*
Y902550D01*
X904040Y900050D01*
G01Y890050D02*
X907760D01*
G01X918300D02*
X919385Y890258D01*
X920625Y890883D01*
X921400Y891925D01*
X921710Y893383D01*
X921400Y894841D01*
X920470Y896092D01*
X919075Y896717D01*
X917525D01*
X916595Y897133D01*
X915820Y898175D01*
X915510Y899633D01*
X915975Y901092D01*
X917060Y902133D01*
X918300Y902550D01*
X919540Y902133D01*
X920625Y901092D01*
X921090Y899633D01*
X920780Y898175D01*
X920005Y897133D01*
X919075Y896717D01*
X917525D01*
X916130Y896092D01*
X915200Y894841D01*
X914890Y893383D01*
X915200Y891925D01*
X915975Y890883D01*
X917215Y890258D01*
X918300Y890050D01*
G01X930390D02*
X930700Y892758D01*
X931165Y895050D01*
X931785Y897133D01*
X932560Y899425D01*
X933800Y902550D01*
X927600D01*
G01X944960Y890050D02*
Y902550D01*
X939225Y893592D01*
X946975D01*
G01X955500Y902550D02*
X954260Y902133D01*
X953330Y901092D01*
X952710Y899842D01*
X952245Y898175D01*
X952090Y896300D01*
X952245Y894425D01*
X952710Y892758D01*
X953330Y891508D01*
X954260Y890467D01*
X955500Y890050D01*
X956740Y890467D01*
X957670Y891508D01*
X958290Y892758D01*
X958755Y894425D01*
X958910Y896300D01*
X958755Y898175D01*
X958290Y899842D01*
X957670Y901092D01*
X956740Y902133D01*
X955500Y902550D01*
G01X967900Y889633D02*
X967590Y889842D01*
Y890258D01*
X967900Y890467D01*
X968210Y890258D01*
Y889842D01*
X967900Y889633D01*
G01X980300Y890050D02*
Y902550D01*
X978440Y900050D01*
G01Y890050D02*
X982160D01*
G01X989755Y895258D02*
X990840Y896717D01*
X991770Y897550D01*
X993010Y897967D01*
X994095Y897550D01*
X994870Y896717D01*
X995490Y895467D01*
X995645Y894008D01*
X995490Y892758D01*
X994870Y891508D01*
X993940Y890467D01*
X992855Y890050D01*
X991615Y890467D01*
X990530Y891716D01*
X989910Y893592D01*
X989755Y895675D01*
X990065Y898383D01*
X990530Y899842D01*
X991305Y901300D01*
X992390Y902342D01*
X993475Y902550D01*
X994560Y902133D01*
X995335Y901092D01*
G01X938910Y865050D02*
Y877550D01*
X933175Y868592D01*
X940925D01*
G01X949140Y865050D02*
X949450Y867758D01*
X949915Y870050D01*
X950535Y872133D01*
X951310Y874425D01*
X952550Y877550D01*
X946350D01*
G01X958905Y870258D02*
X959990Y871717D01*
X960920Y872550D01*
X962160Y872967D01*
X963245Y872550D01*
X964020Y871717D01*
X964640Y870467D01*
X964795Y869008D01*
X964640Y867758D01*
X964020Y866508D01*
X963090Y865467D01*
X962005Y865050D01*
X960765Y865467D01*
X959680Y866716D01*
X959060Y868592D01*
X958905Y870675D01*
X959215Y873383D01*
X959680Y874842D01*
X960455Y876300D01*
X961540Y877342D01*
X962625Y877550D01*
X963710Y877133D01*
X964485Y876092D01*
G01X1091282Y457686D02*
X1090112Y458466D01*
X1088747Y458986D01*
X1087187D01*
X1085432Y458206D01*
X1084067Y456906D01*
X1083092Y455346D01*
X1082312Y452746D01*
X1082117Y450406D01*
X1082507Y448066D01*
X1083092Y446506D01*
X1084262Y444946D01*
X1085627Y443906D01*
X1086992Y443386D01*
X1088357D01*
X1089722Y443906D01*
X1090892Y444686D01*
X1091867Y445726D01*
G01X1106452Y451706D02*
X1107232Y452486D01*
X1107817Y453786D01*
X1108207Y455606D01*
X1107817Y457166D01*
X1107037Y458206D01*
X1105672Y458986D01*
X1100407D01*
Y443386D01*
X1106842D01*
X1108207Y444426D01*
X1108987Y445986D01*
X1109377Y447806D01*
X1108987Y449626D01*
X1107817Y451186D01*
X1106452Y451706D01*
X1100407D01*
G01X1860581Y-774040D02*
G03I-6250J0D01*
G01X1860237Y-726796D02*
G03I-5906J0D01*
G01X1860581Y766166D02*
G03I-6250J0D01*
G01X1968950Y-18500D02*
X1956450D01*
X1958950Y-20360D01*
G01X1968950D02*
Y-16640D01*
G01X1967075Y-9510D02*
X1968117Y-8580D01*
X1968742Y-7495D01*
X1968950Y-6100D01*
X1968533Y-4705D01*
X1967700Y-3620D01*
X1966242Y-2845D01*
X1964575Y-2690D01*
X1962908Y-3000D01*
X1961867Y-3775D01*
X1961033Y-4860D01*
X1960825Y-5945D01*
X1961033Y-7030D01*
X1961867Y-8425D01*
X1956450Y-7960D01*
Y-3775D01*
G01X1968950Y5990D02*
X1966242Y6300D01*
X1963950Y6765D01*
X1961867Y7385D01*
X1959575Y8160D01*
X1956450Y9400D01*
Y3200D01*
G01X1967492Y16065D02*
X1968533Y17150D01*
X1968950Y18390D01*
X1968533Y19630D01*
X1967284Y20715D01*
X1965408Y21490D01*
X1963533Y21800D01*
X1961242D01*
X1959367Y21490D01*
X1957700Y20715D01*
X1956867Y19785D01*
X1956450Y18700D01*
X1956867Y17460D01*
X1957700Y16530D01*
X1958950Y15910D01*
X1960617Y15600D01*
X1962075Y15910D01*
X1963533Y16685D01*
X1964367Y17615D01*
X1964575Y18700D01*
X1964159Y19940D01*
X1963117Y20870D01*
X1961242Y21800D01*
G01X1967075Y27690D02*
X1968117Y28620D01*
X1968742Y29705D01*
X1968950Y31100D01*
X1968533Y32495D01*
X1967700Y33580D01*
X1966242Y34355D01*
X1964575Y34510D01*
X1962908Y34200D01*
X1961867Y33425D01*
X1961033Y32340D01*
X1960825Y31255D01*
X1961033Y30170D01*
X1961867Y28775D01*
X1956450Y29240D01*
Y33425D01*
G01X1969367Y43500D02*
X1969158Y43190D01*
X1968742D01*
X1968533Y43500D01*
X1968742Y43810D01*
X1969158D01*
X1969367Y43500D01*
G01X1968950Y55590D02*
X1966242Y55900D01*
X1963950Y56365D01*
X1961867Y56985D01*
X1959575Y57760D01*
X1956450Y59000D01*
Y52800D01*
G01X1963742Y65355D02*
X1962283Y66440D01*
X1961450Y67370D01*
X1961033Y68610D01*
X1961450Y69695D01*
X1962283Y70470D01*
X1963533Y71090D01*
X1964992Y71245D01*
X1966242Y71090D01*
X1967492Y70470D01*
X1968533Y69540D01*
X1968950Y68455D01*
X1968533Y67215D01*
X1967284Y66130D01*
X1965408Y65510D01*
X1963325Y65355D01*
X1960617Y65665D01*
X1959158Y66130D01*
X1957700Y66905D01*
X1956658Y67990D01*
X1956450Y69075D01*
X1956867Y70160D01*
X1957908Y70935D01*
G01X1993950Y-4090D02*
X1981450D01*
X1990408Y-9825D01*
Y-2075D01*
G01X1981450Y6450D02*
X1981867Y5210D01*
X1982908Y4280D01*
X1984158Y3660D01*
X1985825Y3195D01*
X1987700Y3040D01*
X1989575Y3195D01*
X1991242Y3660D01*
X1992492Y4280D01*
X1993533Y5210D01*
X1993950Y6450D01*
X1993533Y7690D01*
X1992492Y8620D01*
X1991242Y9240D01*
X1989575Y9705D01*
X1987700Y9860D01*
X1985825Y9705D01*
X1984158Y9240D01*
X1982908Y8620D01*
X1981867Y7690D01*
X1981450Y6450D01*
G01X1993950Y18850D02*
X1981450D01*
X1983950Y16990D01*
G01X1993950D02*
Y20710D01*
G01X1994367Y31250D02*
X1994158Y30940D01*
X1993742D01*
X1993533Y31250D01*
X1993742Y31560D01*
X1994158D01*
X1994367Y31250D01*
G01X1983533Y40705D02*
X1982284Y41635D01*
X1981658Y42720D01*
X1981450Y43960D01*
X1981867Y45510D01*
X1982908Y46595D01*
X1984158Y46905D01*
X1985409Y46750D01*
X1986450Y46130D01*
X1988533Y43030D01*
X1989992Y41635D01*
X1992075Y40705D01*
X1993950Y40395D01*
Y46905D01*
G01Y56050D02*
X1981450D01*
X1983950Y54190D01*
G01X1993950D02*
Y57910D01*
G01X2148575Y-398965D02*
X2392984D01*
Y-682980D01*
X2148575D01*
Y-398965D01*
G01X2195819Y-550390D02*
G03I-5906J0D01*
G01X2195612Y-451887D02*
G03I-6250J0D01*
G01X2204087Y-623618D02*
X2213535D01*
G02Y-631492I0J-3937D01*
G01X2204087D01*
G01X2233220Y-623618D02*
X2242669D01*
G01X2233220D02*
G03Y-631492I0J-3937D01*
G01X2242669D01*
M02*
